FILE_TYPE = MACRO_DRAWING;
SET COLOR_WIRE YELLOW;
SET COLOR_PROP ORANGE;
SET COLOR_DOT WHITE;
SET COLOR_ARC YELLOW;
SET COLOR_BODY GREEN;
SET COLOR_NOTE PURPLE;
SET PROP_DISPLAY VALUE;
SET PAGE_NUMBER P161;
FORCEADD OFFPAGE..4
R 2
(-15675 -75);
FORCEPROP 2 LAST $XR0 245 
J 0
(-15927 -75);
DISPLAY 0.638298 (-15927 -75);
PAINT MONO (-15927 -75);
FORCEPROP 2 LAST CDS_LIB standard
J 0
(-15675 -75);
DISPLAY INVISIBLE (-15675 -75);
FORCEPROP 1 LAST OFFPAGE TRUE
J 2
(-16000 -200);
DISPLAY 0.872340 (-16000 -200);
PAINT GREEN (-16000 -200);
DISPLAY INVISIBLE (-16000 -200);
FORCEPROP 1 LAST COMMENT_BODY TRUE
J 2
(-15650 -175);
DISPLAY 0.872340 (-15650 -175);
PAINT GREEN (-15650 -175);
DISPLAY INVISIBLE (-15650 -175);
FORCEPROP 2 LAST PATH I1
J 0
(-15925 -25);
DISPLAY 1.021277 (-15925 -25);
DISPLAY INVISIBLE (-15925 -25);
FORCEADD Q_RES..1
(-13675 650);
FORCEPROP 1 LAST LOCATION R4901
J 0
(-13925 675);
DISPLAY 0.723404 (-13925 675);
PAINT AQUA (-13925 675);
FORCEPROP 0 LAST $SEC 1
J 0
(-13575 725);
DISPLAY 0.680851 (-13575 725);
PAINT MONO (-13575 725);
DISPLAY INVISIBLE (-13575 725);
FORCEPROP 0 LAST CDS_SEC 1
J 0
(-13575 725);
DISPLAY 1.021277 (-13575 725);
DISPLAY INVISIBLE (-13575 725);
FORCEPROP 1 LASTPIN (-13775 650) $PN 1
J 0
(-13763 662);
DISPLAY 0.787234 (-13763 662);
PAINT MONO (-13763 662);
FORCEPROP 1 LASTPIN (-13575 650) $PN 2
J 0
(-13613 662);
DISPLAY 0.787234 (-13613 662);
PAINT MONO (-13613 662);
FORCEPROP 1 LAST MATERIAL CHIP
J 0
(-13750 575);
DISPLAY 0.723404 (-13750 575);
PAINT SKYBLUE (-13750 575);
FORCEPROP 1 LAST VALUE 82K
J 2
(-13625 675);
DISPLAY 0.723404 (-13625 675);
PAINT SKYBLUE (-13625 675);
FORCEPROP 1 LAST TOLERANCE 1%
J 0
(-13575 675);
DISPLAY 0.723404 (-13575 675);
PAINT SKYBLUE (-13575 675);
FORCEPROP 1 LAST PACK_TYPE 0402LF
J 0
(-13575 575);
DISPLAY 0.723404 (-13575 575);
PAINT SKYBLUE (-13575 575);
FORCEPROP 1 LAST WATTAGE 1/16W
J 2
(-13775 575);
DISPLAY 0.723404 (-13775 575);
PAINT SKYBLUE (-13775 575);
FORCEPROP 1 LAST PART_NUMBER CS38202FB01
J 0
(-13825 525);
DISPLAY 0.723404 (-13825 525);
PAINT WHITE (-13825 525);
FORCEPROP 2 LAST CDS_LIB pure_quanta
J 0
(-13675 650);
DISPLAY INVISIBLE (-13675 650);
FORCEPROP 1 LAST PATH I10
J 0
(-13725 800);
DISPLAY 0.978723 (-13725 800);
PAINT WHITE (-13725 800);
DISPLAY INVISIBLE (-13725 800);
FORCEADD GND..1
(-13375 -200);
FORCEPROP 3 LASTPIN (-13375 -150) SIG_NAME GND\g
J 0
(-13365 -140);
DISPLAY 0.659574 (-13365 -140);
PAINT MONO (-13365 -140);
DISPLAY INVISIBLE (-13365 -140);
FORCEPROP 2 LAST ROOM VR_DDR1_POWER_STAGE
J 0
(-13600 -125);
FORCEPROP 1 LAST SIZE 1B
J 0
(-13300 -250);
DISPLAY 0.872340 (-13300 -250);
PAINT AQUA (-13300 -250);
DISPLAY INVISIBLE (-13300 -250);
FORCEPROP 2 LAST CDS_LIB pure_quanta_power
J 0
(-13375 -200);
DISPLAY INVISIBLE (-13375 -200);
FORCEPROP 1 LAST HDL_POWER GND
J 0
(-13375 -50);
DISPLAY 1.170213 (-13375 -50);
PAINT GREEN (-13375 -50);
DISPLAY INVISIBLE (-13375 -50);
FORCEPROP 1 LAST PATH I11
J 0
(-13300 -200);
DISPLAY 0.872340 (-13300 -200);
PAINT AQUA (-13300 -200);
DISPLAY INVISIBLE (-13300 -200);
FORCEADD Q_RES..2
(-13375 50);
FORCEPROP 1 LAST LOCATION R2585
J 0
(-13330 175);
DISPLAY 0.723404 (-13330 175);
PAINT AQUA (-13330 175);
FORCEPROP 0 LAST $SEC 1
J 0
(-13325 225);
DISPLAY INVISIBLE (-13325 225);
FORCEPROP 0 LAST CDS_SEC 1
J 0
(-13325 225);
DISPLAY INVISIBLE (-13325 225);
FORCEPROP 1 LASTPIN (-13375 150) $PN 1
J 0
(-13370 112);
DISPLAY 0.787234 (-13370 112);
PAINT MONO (-13370 112);
DISPLAY INVISIBLE (-13370 112);
FORCEPROP 1 LASTPIN (-13375 -50) $PN 2
J 0
(-13370 -40);
DISPLAY 0.787234 (-13370 -40);
PAINT MONO (-13370 -40);
DISPLAY INVISIBLE (-13370 -40);
FORCEPROP 1 LAST PACK_TYPE 0402LF
J 0
(-13335 -125);
DISPLAY 0.723404 (-13335 -125);
PAINT SKYBLUE (-13335 -125);
FORCEPROP 1 LAST PART_NUMBER CS33162FB02
J 0
(-13335 -75);
DISPLAY 0.723404 (-13335 -75);
PAINT WHITE (-13335 -75);
FORCEPROP 1 LAST MATERIAL CHIP
J 0
(-13335 -25);
DISPLAY 0.723404 (-13335 -25);
PAINT SKYBLUE (-13335 -25);
FORCEPROP 1 LAST WATTAGE 1/16W
J 0
(-13335 25);
DISPLAY 0.723404 (-13335 25);
PAINT SKYBLUE (-13335 25);
FORCEPROP 1 LAST VALUE 31.6K
J 0
(-13330 125);
DISPLAY 0.723404 (-13330 125);
PAINT SKYBLUE (-13330 125);
FORCEPROP 1 LAST TOLERANCE 1%
J 0
(-13330 75);
DISPLAY 0.723404 (-13330 75);
PAINT SKYBLUE (-13330 75);
FORCEPROP 2 LAST CDS_LIB pure_quanta
J 0
(-13375 50);
DISPLAY INVISIBLE (-13375 50);
FORCEPROP 1 LAST PATH I12
J 0
(-13325 225);
DISPLAY 0.978723 (-13325 225);
PAINT WHITE (-13325 225);
DISPLAY INVISIBLE (-13325 225);
FORCEADD Q_CAP..1
(-12750 150);
FORCEPROP 1 LAST LOCATION C1798
J 0
(-12700 275);
DISPLAY 0.723404 (-12700 275);
PAINT AQUA (-12700 275);
FORCEPROP 0 LAST $SEC 1
J 0
(-12700 300);
DISPLAY INVISIBLE (-12700 300);
FORCEPROP 0 LAST CDS_SEC 1
J 0
(-12700 300);
DISPLAY INVISIBLE (-12700 300);
FORCEPROP 1 LASTPIN (-12750 250) $PN 1
J 0
(-12740 230);
DISPLAY 0.787234 (-12740 230);
PAINT MONO (-12740 230);
DISPLAY INVISIBLE (-12740 230);
FORCEPROP 1 LASTPIN (-12750 50) $PN 2
J 0
(-12740 30);
DISPLAY 0.787234 (-12740 30);
PAINT MONO (-12740 30);
DISPLAY INVISIBLE (-12740 30);
FORCEPROP 1 LAST PACK_TYPE C0402
J 0
(-12700 -25);
DISPLAY 0.723404 (-12700 -25);
PAINT SKYBLUE (-12700 -25);
FORCEPROP 1 LAST VALUE 100NF
J 0
(-12700 225);
DISPLAY 0.723404 (-12700 225);
PAINT SKYBLUE (-12700 225);
FORCEPROP 1 LAST PART_NUMBER CH4106K1B01
J 0
(-12700 25);
DISPLAY 0.723404 (-12700 25);
PAINT WHITE (-12700 25);
FORCEPROP 1 LAST MATERIAL X7R
J 0
(-12700 75);
DISPLAY 0.723404 (-12700 75);
PAINT SKYBLUE (-12700 75);
FORCEPROP 1 LAST VOLTAGE 50V
J 0
(-12700 175);
DISPLAY 0.723404 (-12700 175);
PAINT SKYBLUE (-12700 175);
FORCEPROP 1 LAST TOLERANCE 10%
J 0
(-12700 125);
DISPLAY 0.723404 (-12700 125);
PAINT SKYBLUE (-12700 125);
FORCEPROP 2 LAST CDS_LIB pure_quanta
J 0
(-12750 150);
DISPLAY INVISIBLE (-12750 150);
FORCEPROP 1 LAST PATH I13
J 0
(-12700 300);
DISPLAY 0.978723 (-12700 300);
PAINT WHITE (-12700 300);
DISPLAY INVISIBLE (-12700 300);
FORCEADD UNIVERSAL_GND..1
(-12750 -200);
FORCEPROP 3 LASTPIN (-12750 -150) SIG_NAME AGND_HSC\g
J 0
(-12740 -140);
DISPLAY 0.659574 (-12740 -140);
PAINT MONO (-12740 -140);
DISPLAY INVISIBLE (-12740 -140);
FORCEPROP 1 LAST HDL_POWER AGND_HSC
J 1
(-12725 -275);
DISPLAY 0.723404 (-12725 -275);
PAINT GREEN (-12725 -275);
FORCEPROP 2 LAST CDS_LIB pure_quanta_power
J 0
(-12750 -200);
DISPLAY INVISIBLE (-12750 -200);
FORCEPROP 1 LAST PATH I14
J 0
(-12675 -200);
DISPLAY 0.872340 (-12675 -200);
PAINT AQUA (-12675 -200);
DISPLAY INVISIBLE (-12675 -200);
FORCEADD OFFPAGE..4
(-13425 875);
FORCEPROP 2 LAST $XR0 301 
J 0
(-13239 875);
DISPLAY 0.638298 (-13239 875);
PAINT MONO (-13239 875);
FORCEPROP 2 LAST CDS_LIB standard
J 2
(-13425 875);
DISPLAY INVISIBLE (-13425 875);
FORCEPROP 1 LAST OFFPAGE TRUE
J 0
(-13100 750);
DISPLAY 0.872340 (-13100 750);
PAINT GREEN (-13100 750);
DISPLAY INVISIBLE (-13100 750);
FORCEPROP 1 LAST COMMENT_BODY TRUE
J 0
(-13450 775);
DISPLAY 0.872340 (-13450 775);
PAINT GREEN (-13450 775);
DISPLAY INVISIBLE (-13450 775);
FORCEPROP 2 LAST PATH I15
J 0
(-13225 925);
DISPLAY 1.021277 (-13225 925);
DISPLAY INVISIBLE (-13225 925);
FORCEADD OFFPAGE..5
R 2
(-12600 650);
FORCEPROP 2 LAST $XR0 301 
J 0
(-12411 650);
DISPLAY 0.638298 (-12411 650);
PAINT MONO (-12411 650);
FORCEPROP 2 LAST CDS_LIB standard
J 2
(-12600 650);
DISPLAY INVISIBLE (-12600 650);
FORCEPROP 1 LAST OFFPAGE TRUE
J 2
(-12925 525);
DISPLAY 0.872340 (-12925 525);
PAINT AQUA (-12925 525);
DISPLAY INVISIBLE (-12925 525);
FORCEPROP 1 LAST COMMENT_BODY TRUE
J 2
(-12700 575);
DISPLAY 1.170213 (-12700 575);
PAINT GREEN (-12700 575);
DISPLAY INVISIBLE (-12700 575);
FORCEPROP 2 LAST PATH I16
J 0
(-12400 700);
DISPLAY 1.021277 (-12400 700);
DISPLAY INVISIBLE (-12400 700);
FORCEADD UNIVERSAL_GND..1
(-12850 1550);
FORCEPROP 3 LASTPIN (-12850 1600) SIG_NAME AGND_HSC\g
J 0
(-12840 1610);
DISPLAY 0.659574 (-12840 1610);
PAINT MONO (-12840 1610);
DISPLAY INVISIBLE (-12840 1610);
FORCEPROP 1 LAST HDL_POWER AGND_HSC
J 1
(-12850 1475);
DISPLAY 0.723404 (-12850 1475);
PAINT GREEN (-12850 1475);
FORCEPROP 2 LAST CDS_LIB pure_quanta_power
J 0
(-12850 1550);
DISPLAY INVISIBLE (-12850 1550);
FORCEPROP 1 LAST PATH I17
J 0
(-12775 1550);
DISPLAY 0.872340 (-12775 1550);
PAINT AQUA (-12775 1550);
DISPLAY INVISIBLE (-12775 1550);
FORCEADD GND..1
(-11775 775);
FORCEPROP 3 LASTPIN (-11775 825) SIG_NAME GND\g
J 0
(-11765 835);
DISPLAY 0.659574 (-11765 835);
PAINT MONO (-11765 835);
DISPLAY INVISIBLE (-11765 835);
FORCEPROP 2 LAST ROOM VR_DDR1_POWER_STAGE
J 0
(-12000 850);
FORCEPROP 1 LAST SIZE 1B
J 0
(-11700 725);
DISPLAY 0.872340 (-11700 725);
PAINT AQUA (-11700 725);
DISPLAY INVISIBLE (-11700 725);
FORCEPROP 2 LAST CDS_LIB pure_quanta_power
J 0
(-11775 775);
DISPLAY INVISIBLE (-11775 775);
FORCEPROP 1 LAST HDL_POWER GND
J 0
(-11775 925);
DISPLAY 1.170213 (-11775 925);
PAINT GREEN (-11775 925);
DISPLAY INVISIBLE (-11775 925);
FORCEPROP 1 LAST PATH I18
J 0
(-11700 775);
DISPLAY 0.872340 (-11700 775);
PAINT AQUA (-11700 775);
DISPLAY INVISIBLE (-11700 775);
FORCEADD Q_RES..1
(-11450 1025);
FORCEPROP 1 LAST LOCATION PR3002
J 0
(-11500 1075);
DISPLAY 0.723404 (-11500 1075);
PAINT AQUA (-11500 1075);
FORCEPROP 0 LAST $SEC 1
J 0
(-11325 1125);
DISPLAY 0.680851 (-11325 1125);
PAINT MONO (-11325 1125);
DISPLAY INVISIBLE (-11325 1125);
FORCEPROP 0 LAST CDS_SEC 1
J 0
(-11325 1125);
DISPLAY 1.021277 (-11325 1125);
DISPLAY INVISIBLE (-11325 1125);
FORCEPROP 1 LASTPIN (-11550 1025) $PN 1
J 0
(-11538 1037);
DISPLAY 0.787234 (-11538 1037);
PAINT MONO (-11538 1037);
FORCEPROP 1 LASTPIN (-11350 1025) $PN 2
J 0
(-11388 1037);
DISPLAY 0.787234 (-11388 1037);
PAINT MONO (-11388 1037);
FORCEPROP 1 LAST PART_NUMBER CS00002JB13
J 0
(-11325 1075);
DISPLAY 0.723404 (-11325 1075);
PAINT WHITE (-11325 1075);
FORCEPROP 1 LAST VALUE 0
J 2
(-11500 950);
DISPLAY 0.723404 (-11500 950);
PAINT SKYBLUE (-11500 950);
FORCEPROP 1 LAST MATERIAL CHIP
J 0
(-11525 850);
DISPLAY 0.723404 (-11525 850);
PAINT SKYBLUE (-11525 850);
FORCEPROP 1 LAST WATTAGE 1/16W
J 2
(-11550 850);
DISPLAY 0.723404 (-11550 850);
PAINT SKYBLUE (-11550 850);
FORCEPROP 1 LAST TOLERANCE 5%
J 0
(-11350 950);
DISPLAY 0.723404 (-11350 950);
PAINT SKYBLUE (-11350 950);
FORCEPROP 1 LAST PACK_TYPE 0402LF
J 0
(-11275 850);
DISPLAY 0.723404 (-11275 850);
PAINT SKYBLUE (-11275 850);
FORCEPROP 2 LAST CDS_LIB pure_quanta
J 0
(-11450 1025);
DISPLAY INVISIBLE (-11450 1025);
FORCEPROP 1 LAST PATH I19
J 0
(-11500 1175);
DISPLAY 0.978723 (-11500 1175);
PAINT WHITE (-11500 1175);
DISPLAY INVISIBLE (-11500 1175);
FORCEADD UNIVERSAL_GND..1
(-15500 -525);
FORCEPROP 3 LASTPIN (-15500 -475) SIG_NAME GND\g
J 0
(-15490 -465);
DISPLAY 0.659574 (-15490 -465);
PAINT MONO (-15490 -465);
DISPLAY INVISIBLE (-15490 -465);
FORCEPROP 2 LAST CDS_LIB pure_quanta_power
J 0
(-15500 -525);
DISPLAY INVISIBLE (-15500 -525);
FORCEPROP 1 LAST HDL_POWER GND
J 1
(-15475 -600);
DISPLAY 0.872340 (-15475 -600);
PAINT GREEN (-15475 -600);
DISPLAY INVISIBLE (-15475 -600);
FORCEPROP 1 LAST PATH I2
J 0
(-15425 -525);
DISPLAY 0.872340 (-15425 -525);
PAINT AQUA (-15425 -525);
DISPLAY INVISIBLE (-15425 -525);
FORCEADD UNIVERSAL_GND..1
(-11000 825);
FORCEPROP 3 LASTPIN (-11000 875) SIG_NAME AGND_HSC\g
J 0
(-10990 885);
DISPLAY 0.659574 (-10990 885);
PAINT MONO (-10990 885);
DISPLAY INVISIBLE (-10990 885);
FORCEPROP 1 LAST HDL_POWER AGND_HSC
J 1
(-10975 750);
DISPLAY 0.723404 (-10975 750);
PAINT GREEN (-10975 750);
FORCEPROP 2 LAST CDS_LIB pure_quanta_power
J 0
(-11000 825);
DISPLAY INVISIBLE (-11000 825);
FORCEPROP 1 LAST PATH I20
J 0
(-10925 825);
DISPLAY 0.872340 (-10925 825);
PAINT AQUA (-10925 825);
DISPLAY INVISIBLE (-10925 825);
FORCEADD UNIVERSAL_GND..1
(-9975 1250);
FORCEPROP 3 LASTPIN (-9975 1300) SIG_NAME AGND_HSC\g
J 0
(-9965 1310);
DISPLAY 0.659574 (-9965 1310);
PAINT MONO (-9965 1310);
DISPLAY INVISIBLE (-9965 1310);
FORCEPROP 1 LAST HDL_POWER AGND_HSC
J 1
(-9950 1175);
DISPLAY 0.723404 (-9950 1175);
PAINT GREEN (-9950 1175);
FORCEPROP 2 LAST CDS_LIB pure_quanta_power
J 0
(-9975 1250);
DISPLAY INVISIBLE (-9975 1250);
FORCEPROP 1 LAST PATH I21
J 0
(-9900 1250);
DISPLAY 0.872340 (-9900 1250);
PAINT AQUA (-9900 1250);
DISPLAY INVISIBLE (-9900 1250);
FORCEADD Q_RES..2
(-9975 1450);
FORCEPROP 1 LAST LOCATION R1117
J 0
(-9920 1625);
DISPLAY 0.723404 (-9920 1625);
PAINT AQUA (-9920 1625);
FORCEPROP 0 LAST $SEC 1
J 0
(-9900 1675);
DISPLAY 0.680851 (-9900 1675);
PAINT MONO (-9900 1675);
DISPLAY INVISIBLE (-9900 1675);
FORCEPROP 0 LAST CDS_SEC 1
J 0
(-9900 1675);
DISPLAY 1.021277 (-9900 1675);
DISPLAY INVISIBLE (-9900 1675);
FORCEPROP 1 LASTPIN (-9975 1550) $PN 1
J 0
(-9970 1512);
DISPLAY 0.787234 (-9970 1512);
PAINT MONO (-9970 1512);
FORCEPROP 1 LASTPIN (-9975 1350) $PN 2
J 0
(-9970 1360);
DISPLAY 0.787234 (-9970 1360);
PAINT MONO (-9970 1360);
FORCEPROP 1 LAST WATTAGE 1/16W
J 0
(-9925 1475);
DISPLAY 0.723404 (-9925 1475);
PAINT SKYBLUE (-9925 1475);
FORCEPROP 1 LAST VALUE 6.19K
J 0
(-9920 1575);
DISPLAY 0.723404 (-9920 1575);
PAINT SKYBLUE (-9920 1575);
FORCEPROP 1 LAST MATERIAL CHIP
J 0
(-9925 1425);
DISPLAY 0.723404 (-9925 1425);
PAINT SKYBLUE (-9925 1425);
FORCEPROP 1 LAST TOLERANCE 1%
J 0
(-9920 1525);
DISPLAY 0.723404 (-9920 1525);
PAINT SKYBLUE (-9920 1525);
FORCEPROP 1 LAST PART_NUMBER CS26192FB03
J 0
(-9925 1375);
DISPLAY 0.723404 (-9925 1375);
PAINT WHITE (-9925 1375);
FORCEPROP 1 LAST PACK_TYPE 0402LF
J 0
(-9925 1325);
DISPLAY 0.723404 (-9925 1325);
PAINT SKYBLUE (-9925 1325);
FORCEPROP 2 LAST CDS_LIB pure_quanta
J 0
(-9975 1450);
DISPLAY INVISIBLE (-9975 1450);
FORCEPROP 1 LAST PATH I22
J 0
(-9925 1625);
DISPLAY 0.978723 (-9925 1625);
PAINT WHITE (-9925 1625);
DISPLAY INVISIBLE (-9925 1625);
FORCEADD OFFPAGE..5
(-15800 2500);
FORCEPROP 2 LAST $XR2 215 
J 0
(-16055 2464);
DISPLAY 0.638298 (-16055 2464);
PAINT MONO (-16055 2464);
FORCEPROP 2 LAST $XR1 183 
J 0
(-16175 2500);
DISPLAY 0.638298 (-16175 2500);
PAINT MONO (-16175 2500);
FORCEPROP 2 LAST $XR0 228 
J 0
(-16055 2500);
DISPLAY 0.638298 (-16055 2500);
PAINT MONO (-16055 2500);
FORCEPROP 2 LAST CDS_LIB standard
J 2
(-15800 2500);
DISPLAY INVISIBLE (-15800 2500);
FORCEPROP 1 LAST OFFPAGE TRUE
J 0
(-15475 2375);
DISPLAY 0.872340 (-15475 2375);
PAINT AQUA (-15475 2375);
DISPLAY INVISIBLE (-15475 2375);
FORCEPROP 1 LAST COMMENT_BODY TRUE
J 0
(-15700 2425);
DISPLAY 1.170213 (-15700 2425);
PAINT GREEN (-15700 2425);
DISPLAY INVISIBLE (-15700 2425);
FORCEPROP 2 LAST PATH I23
J 0
(-16050 2550);
DISPLAY 1.021277 (-16050 2550);
DISPLAY INVISIBLE (-16050 2550);
FORCEADD Q_RES..1
(-14625 2500);
FORCEPROP 1 LAST $LOCATION R3924
J 0
(-14975 2500);
DISPLAY 0.723404 (-14975 2500);
PAINT AQUA (-14975 2500);
FORCEPROP 0 LAST CDS_LOCATION R3924
J 0
(-14250 2575);
DISPLAY 1.021277 (-14250 2575);
DISPLAY INVISIBLE (-14250 2575);
FORCEPROP 0 LAST $SEC 1
J 0
(-14250 2575);
DISPLAY 0.680851 (-14250 2575);
PAINT MONO (-14250 2575);
DISPLAY INVISIBLE (-14250 2575);
FORCEPROP 0 LAST CDS_SEC 1
J 0
(-14250 2575);
DISPLAY 1.021277 (-14250 2575);
DISPLAY INVISIBLE (-14250 2575);
FORCEPROP 1 LASTPIN (-14725 2500) $PN 1
J 0
(-14713 2512);
DISPLAY 0.787234 (-14713 2512);
PAINT MONO (-14713 2512);
FORCEPROP 1 LASTPIN (-14525 2500) $PN 2
J 0
(-14563 2512);
DISPLAY 0.787234 (-14563 2512);
PAINT MONO (-14563 2512);
FORCEPROP 1 LAST MATERIAL CHIP
J 0
(-14200 2450);
DISPLAY 0.723404 (-14200 2450);
PAINT SKYBLUE (-14200 2450);
FORCEPROP 1 LAST VALUE 0
J 2
(-14500 2525);
DISPLAY 0.723404 (-14500 2525);
PAINT SKYBLUE (-14500 2525);
FORCEPROP 1 LAST TOLERANCE 5%
J 0
(-14550 2450);
DISPLAY 0.723404 (-14550 2450);
PAINT SKYBLUE (-14550 2450);
FORCEPROP 1 LAST PART_NUMBER CS00002JB13
J 0
(-14975 2450);
DISPLAY 0.723404 (-14975 2450);
PAINT WHITE (-14975 2450);
FORCEPROP 1 LAST PACK_TYPE 0402LF
J 0
(-14425 2450);
DISPLAY 0.723404 (-14425 2450);
PAINT SKYBLUE (-14425 2450);
FORCEPROP 1 LAST WATTAGE 1/16W
J 2
(-14250 2525);
DISPLAY 0.723404 (-14250 2525);
PAINT SKYBLUE (-14250 2525);
FORCEPROP 2 LAST CDS_LIB pure_quanta
J 0
(-14625 2500);
DISPLAY INVISIBLE (-14625 2500);
FORCEPROP 1 LAST PATH I24
J 0
(-14675 2650);
DISPLAY 0.978723 (-14675 2650);
PAINT WHITE (-14675 2650);
DISPLAY INVISIBLE (-14675 2650);
FORCEADD OFFPAGE..3
R 2
(-15100 3075);
FORCEPROP 2 LAST $XR0 241 
J 0
(-15380 3075);
DISPLAY 0.638298 (-15380 3075);
PAINT MONO (-15380 3075);
FORCEPROP 2 LAST CDS_LIB standard
J 2
(-15100 3075);
DISPLAY INVISIBLE (-15100 3075);
FORCEPROP 1 LAST OFFPAGE TRUE
J 2
(-15425 2950);
DISPLAY 0.872340 (-15425 2950);
PAINT GREEN (-15425 2950);
DISPLAY INVISIBLE (-15425 2950);
FORCEPROP 1 LAST COMMENT_BODY TRUE
J 2
(-15050 2975);
DISPLAY 0.872340 (-15050 2975);
PAINT GREEN (-15050 2975);
DISPLAY INVISIBLE (-15050 2975);
FORCEPROP 2 LAST PATH I25
J 0
(-15375 3125);
DISPLAY 1.021277 (-15375 3125);
DISPLAY INVISIBLE (-15375 3125);
FORCEADD OFFPAGE..4
R 2
(-15100 3175);
FORCEPROP 2 LAST $XR0 241 
J 0
(-15352 3175);
DISPLAY 0.638298 (-15352 3175);
PAINT MONO (-15352 3175);
FORCEPROP 2 LAST CDS_LIB standard
J 0
(-15100 3175);
DISPLAY INVISIBLE (-15100 3175);
FORCEPROP 1 LAST OFFPAGE TRUE
J 2
(-15425 3050);
DISPLAY 0.872340 (-15425 3050);
PAINT GREEN (-15425 3050);
DISPLAY INVISIBLE (-15425 3050);
FORCEPROP 1 LAST COMMENT_BODY TRUE
J 2
(-15075 3075);
DISPLAY 0.872340 (-15075 3075);
PAINT GREEN (-15075 3075);
DISPLAY INVISIBLE (-15075 3075);
FORCEPROP 2 LAST PATH I26
J 0
(-15350 3225);
DISPLAY 1.021277 (-15350 3225);
DISPLAY INVISIBLE (-15350 3225);
FORCEADD Q_CAP..1
(-15425 3625);
FORCEPROP 1 LAST LOCATION PC2186
J 0
(-15350 3775);
DISPLAY 0.723404 (-15350 3775);
PAINT AQUA (-15350 3775);
FORCEPROP 0 LAST $SEC 1
J 0
(-15350 3825);
DISPLAY 0.680851 (-15350 3825);
PAINT MONO (-15350 3825);
DISPLAY INVISIBLE (-15350 3825);
FORCEPROP 0 LAST CDS_SEC 1
J 0
(-15350 3825);
DISPLAY 1.021277 (-15350 3825);
DISPLAY INVISIBLE (-15350 3825);
FORCEPROP 1 LASTPIN (-15425 3725) $PN 1
J 0
(-15415 3705);
DISPLAY 0.787234 (-15415 3705);
PAINT MONO (-15415 3705);
FORCEPROP 1 LASTPIN (-15425 3525) $PN 2
J 0
(-15415 3505);
DISPLAY 0.787234 (-15415 3505);
PAINT MONO (-15415 3505);
FORCEPROP 1 LAST VALUE 1UF
J 0
(-15350 3725);
DISPLAY 0.723404 (-15350 3725);
PAINT SKYBLUE (-15350 3725);
FORCEPROP 1 LAST VOLTAGE 25V
J 0
(-15350 3675);
DISPLAY 0.723404 (-15350 3675);
PAINT SKYBLUE (-15350 3675);
FORCEPROP 1 LAST MATERIAL X6S
J 0
(-15350 3625);
DISPLAY 0.723404 (-15350 3625);
PAINT SKYBLUE (-15350 3625);
FORCEPROP 1 LAST PART_NUMBER CH5104KEB02
J 0
(-15350 3575);
DISPLAY 0.723404 (-15350 3575);
PAINT WHITE (-15350 3575);
FORCEPROP 1 LAST PACK_TYPE C0402
J 0
(-15350 3525);
DISPLAY 0.723404 (-15350 3525);
PAINT SKYBLUE (-15350 3525);
FORCEPROP 2 LAST CDS_LIB pure_quanta
J 0
(-15425 3625);
DISPLAY INVISIBLE (-15425 3625);
FORCEPROP 1 LAST TOLERANCE 10%
J 0
(-15375 3575);
DISPLAY 0.978723 (-15375 3575);
PAINT SKYBLUE (-15375 3575);
DISPLAY INVISIBLE (-15375 3575);
FORCEPROP 1 LAST PATH I27
J 0
(-15375 3775);
DISPLAY 0.978723 (-15375 3775);
PAINT WHITE (-15375 3775);
DISPLAY INVISIBLE (-15375 3775);
FORCEADD CONN3_210HP1030BR1..1
R 2
(-14850 2800);
PAINT AQUA (-14850 2800);
FORCEPROP 1 LAST $LOCATION JP10
J 2
(-14925 2775);
DISPLAY 0.723404 (-14925 2775);
PAINT AQUA (-14925 2775);
FORCEPROP 0 LAST CDS_LOCATION JP10
J 0
(-14900 2925);
DISPLAY 1.021277 (-14900 2925);
DISPLAY INVISIBLE (-14900 2925);
FORCEPROP 0 LAST $SEC 1
J 0
(-14900 2925);
DISPLAY 0.680851 (-14900 2925);
PAINT MONO (-14900 2925);
DISPLAY INVISIBLE (-14900 2925);
FORCEPROP 0 LAST CDS_SEC 1
J 0
(-14900 2925);
DISPLAY 1.021277 (-14900 2925);
DISPLAY INVISIBLE (-14900 2925);
FORCEPROP 0 LASTPIN (-14650 2850) $PN 1
J 0
(-14640 2860);
DISPLAY 0.680851 (-14640 2860);
PAINT MONO (-14640 2860);
FORCEPROP 0 LASTPIN (-14650 2800) $PN 2
J 0
(-14640 2810);
DISPLAY 0.680851 (-14640 2810);
PAINT MONO (-14640 2810);
FORCEPROP 0 LASTPIN (-14650 2750) $PN 3
J 0
(-14640 2760);
DISPLAY 0.680851 (-14640 2760);
PAINT MONO (-14640 2760);
FORCEPROP 1 LAST MATERIAL IO
J 2
(-14925 2674);
DISPLAY 0.723404 (-14925 2674);
PAINT SKYBLUE (-14925 2674);
FORCEPROP 2 LAST PART_TYPE THLF
J 2
(-14900 2825);
DISPLAY 1.021277 (-14900 2825);
FORCEPROP 2 LAST VALUE CONN3_210-HP1-030BR1
J 2
(-14900 2875);
DISPLAY 0.723404 (-14900 2875);
PAINT AQUA (-14900 2875);
FORCEPROP 1 LAST PART_NUMBER DFHD03MS213
J 2
(-14925 2725);
DISPLAY 0.723404 (-14925 2725);
PAINT WHITE (-14925 2725);
FORCEPROP 1 LAST NEEDS_NO_SIZE TRUE
J 2
(-14850 2800);
DISPLAY 0.723404 (-14850 2800);
PAINT GREEN (-14850 2800);
DISPLAY INVISIBLE (-14850 2800);
FORCEPROP 1 LAST CDS_LMAN_SYM_OUTLINE -50,100,50,-100
J 2
(-14850 2800);
DISPLAY 0.468085 (-14850 2800);
PAINT GREEN (-14850 2800);
DISPLAY INVISIBLE (-14850 2800);
FORCEPROP 2 LAST CDS_LIB pure_quanta
J 2
(-14850 2800);
DISPLAY INVISIBLE (-14850 2800);
FORCEPROP 1 LAST PATH I28
J 2
(-14850 2800);
DISPLAY 0.723404 (-14850 2800);
PAINT GREEN (-14850 2800);
DISPLAY INVISIBLE (-14850 2800);
FORCEADD UNIVERSAL_GND..1
(-14925 3350);
FORCEPROP 3 LASTPIN (-14925 3400) SIG_NAME AGND_HSC\g
J 0
(-14915 3410);
DISPLAY 0.659574 (-14915 3410);
PAINT MONO (-14915 3410);
DISPLAY INVISIBLE (-14915 3410);
FORCEPROP 1 LAST HDL_POWER AGND_HSC
J 1
(-14900 3275);
DISPLAY 0.723404 (-14900 3275);
PAINT GREEN (-14900 3275);
FORCEPROP 2 LAST CDS_LIB pure_quanta_power
J 0
(-14925 3350);
DISPLAY INVISIBLE (-14925 3350);
FORCEPROP 1 LAST PATH I29
J 0
(-14850 3350);
DISPLAY 0.872340 (-14850 3350);
PAINT AQUA (-14850 3350);
DISPLAY INVISIBLE (-14850 3350);
FORCEADD GND..1
(-14275 -525);
FORCEPROP 3 LASTPIN (-14275 -475) SIG_NAME GND\g
J 0
(-14265 -465);
DISPLAY 0.659574 (-14265 -465);
PAINT MONO (-14265 -465);
DISPLAY INVISIBLE (-14265 -465);
FORCEPROP 2 LAST ROOM VR_DDR1_POWER_STAGE
J 0
(-14500 -450);
FORCEPROP 1 LAST SIZE 1B
J 0
(-14200 -575);
DISPLAY 0.872340 (-14200 -575);
PAINT AQUA (-14200 -575);
DISPLAY INVISIBLE (-14200 -575);
FORCEPROP 2 LAST CDS_LIB pure_quanta_power
J 0
(-14275 -525);
DISPLAY INVISIBLE (-14275 -525);
FORCEPROP 1 LAST HDL_POWER GND
J 0
(-14275 -375);
DISPLAY 1.170213 (-14275 -375);
PAINT GREEN (-14275 -375);
DISPLAY INVISIBLE (-14275 -375);
FORCEPROP 1 LAST PATH I3
J 0
(-14200 -525);
DISPLAY 0.872340 (-14200 -525);
PAINT AQUA (-14200 -525);
DISPLAY INVISIBLE (-14200 -525);
FORCEADD Q_CAP..1
(-14925 3600);
FORCEPROP 1 LAST LOCATION PC2187
J 0
(-14850 3775);
DISPLAY 0.723404 (-14850 3775);
PAINT AQUA (-14850 3775);
FORCEPROP 0 LAST $SEC 1
J 0
(-14850 3825);
DISPLAY 0.680851 (-14850 3825);
PAINT MONO (-14850 3825);
DISPLAY INVISIBLE (-14850 3825);
FORCEPROP 0 LAST CDS_SEC 1
J 0
(-14850 3825);
DISPLAY 1.021277 (-14850 3825);
DISPLAY INVISIBLE (-14850 3825);
FORCEPROP 1 LASTPIN (-14925 3700) $PN 1
J 0
(-14915 3680);
DISPLAY 0.787234 (-14915 3680);
PAINT MONO (-14915 3680);
FORCEPROP 1 LASTPIN (-14925 3500) $PN 2
J 0
(-14915 3480);
DISPLAY 0.787234 (-14915 3480);
PAINT MONO (-14915 3480);
FORCEPROP 1 LAST PACK_TYPE C0402
J 0
(-14850 3525);
DISPLAY 0.723404 (-14850 3525);
PAINT SKYBLUE (-14850 3525);
FORCEPROP 1 LAST VALUE 1UF
J 0
(-14850 3725);
DISPLAY 0.723404 (-14850 3725);
PAINT SKYBLUE (-14850 3725);
FORCEPROP 1 LAST VOLTAGE 25V
J 0
(-14850 3675);
DISPLAY 0.723404 (-14850 3675);
PAINT SKYBLUE (-14850 3675);
FORCEPROP 1 LAST MATERIAL X6S
J 0
(-14850 3625);
DISPLAY 0.723404 (-14850 3625);
PAINT SKYBLUE (-14850 3625);
FORCEPROP 1 LAST PART_NUMBER CH5104KEB02
J 0
(-14850 3575);
DISPLAY 0.723404 (-14850 3575);
PAINT WHITE (-14850 3575);
FORCEPROP 1 LAST TOLERANCE 10%
J 0
(-14875 3550);
DISPLAY 0.978723 (-14875 3550);
PAINT SKYBLUE (-14875 3550);
DISPLAY INVISIBLE (-14875 3550);
FORCEPROP 2 LAST CDS_LIB pure_quanta
J 0
(-14925 3600);
DISPLAY INVISIBLE (-14925 3600);
FORCEPROP 1 LAST PATH I30
J 0
(-14875 3750);
DISPLAY 0.978723 (-14875 3750);
PAINT WHITE (-14875 3750);
DISPLAY INVISIBLE (-14875 3750);
FORCEADD OFFPAGE..5
(-14300 2150);
FORCEPROP 2 LAST $XR1 303 
J 0
(-14705 2150);
DISPLAY 0.638298 (-14705 2150);
PAINT MONO (-14705 2150);
FORCEPROP 2 LAST $XR0 302 
J 0
(-14585 2150);
DISPLAY 0.638298 (-14585 2150);
PAINT MONO (-14585 2150);
FORCEPROP 2 LAST CDS_LIB standard
J 0
(-14300 2150);
DISPLAY INVISIBLE (-14300 2150);
FORCEPROP 1 LAST OFFPAGE TRUE
J 0
(-13975 2025);
DISPLAY 0.872340 (-13975 2025);
PAINT AQUA (-13975 2025);
DISPLAY INVISIBLE (-13975 2025);
FORCEPROP 1 LAST COMMENT_BODY TRUE
J 0
(-14200 2075);
DISPLAY 1.170213 (-14200 2075);
PAINT GREEN (-14200 2075);
DISPLAY INVISIBLE (-14200 2075);
FORCEPROP 2 LAST PATH I31
J 0
(-14575 2200);
DISPLAY 1.021277 (-14575 2200);
DISPLAY INVISIBLE (-14575 2200);
FORCEADD OFFPAGE..4
R 2
(-14300 2300);
FORCEPROP 2 LAST $XR0 301 
J 0
(-14552 2300);
DISPLAY 0.638298 (-14552 2300);
PAINT MONO (-14552 2300);
FORCEPROP 2 LAST CDS_LIB standard
J 0
(-14300 2300);
DISPLAY INVISIBLE (-14300 2300);
FORCEPROP 1 LAST OFFPAGE TRUE
J 2
(-14625 2175);
DISPLAY 0.872340 (-14625 2175);
PAINT GREEN (-14625 2175);
DISPLAY INVISIBLE (-14625 2175);
FORCEPROP 1 LAST COMMENT_BODY TRUE
J 2
(-14275 2200);
DISPLAY 0.872340 (-14275 2200);
PAINT GREEN (-14275 2200);
DISPLAY INVISIBLE (-14275 2200);
FORCEPROP 2 LAST PATH I32
J 0
(-14550 2350);
DISPLAY 1.021277 (-14550 2350);
DISPLAY INVISIBLE (-14550 2350);
FORCEADD GND..1
(-14575 2650);
FORCEPROP 3 LASTPIN (-14575 2700) SIG_NAME GND\g
J 0
(-14565 2710);
DISPLAY 0.659574 (-14565 2710);
PAINT MONO (-14565 2710);
DISPLAY INVISIBLE (-14565 2710);
FORCEPROP 2 LAST ROOM VR_DDR1_POWER_STAGE
J 0
(-14800 2725);
FORCEPROP 2 LAST CDS_LIB pure_quanta_power
J 0
(-14575 2650);
DISPLAY INVISIBLE (-14575 2650);
FORCEPROP 1 LAST SIZE 1B
J 0
(-14500 2600);
DISPLAY 0.872340 (-14500 2600);
PAINT AQUA (-14500 2600);
DISPLAY INVISIBLE (-14500 2600);
FORCEPROP 1 LAST HDL_POWER GND
J 0
(-14575 2800);
DISPLAY 1.170213 (-14575 2800);
PAINT GREEN (-14575 2800);
DISPLAY INVISIBLE (-14575 2800);
FORCEPROP 1 LAST PATH I33
J 0
(-14500 2650);
DISPLAY 0.872340 (-14500 2650);
PAINT AQUA (-14500 2650);
DISPLAY INVISIBLE (-14500 2650);
FORCEADD Q_RES..1
R 1
(-14225 2675);
FORCEPROP 1 LAST $LOCATION R3925
J 0
(-14150 2825);
DISPLAY 0.723404 (-14150 2825);
PAINT AQUA (-14150 2825);
FORCEPROP 0 LAST CDS_LOCATION R3925
R 1
J 0
(-14150 2875);
DISPLAY 1.021277 (-14150 2875);
DISPLAY INVISIBLE (-14150 2875);
FORCEPROP 0 LAST $SEC 1
R 1
J 0
(-14150 2875);
DISPLAY 0.680851 (-14150 2875);
PAINT MONO (-14150 2875);
DISPLAY INVISIBLE (-14150 2875);
FORCEPROP 0 LAST CDS_SEC 1
R 1
J 0
(-14150 2875);
DISPLAY 1.021277 (-14150 2875);
DISPLAY INVISIBLE (-14150 2875);
FORCEPROP 1 LASTPIN (-14225 2575) $PN 1
R 1
J 0
(-14237 2587);
DISPLAY 0.787234 (-14237 2587);
PAINT MONO (-14237 2587);
FORCEPROP 1 LASTPIN (-14225 2775) $PN 2
R 1
J 0
(-14237 2737);
DISPLAY 0.787234 (-14237 2737);
PAINT MONO (-14237 2737);
FORCEPROP 1 LAST WATTAGE 1/16W
J 0
(-14150 2625);
DISPLAY 0.723404 (-14150 2625);
PAINT SKYBLUE (-14150 2625);
FORCEPROP 1 LAST MATERIAL CHIP
J 0
(-14150 2525);
DISPLAY 0.638298 (-14150 2525);
PAINT SKYBLUE (-14150 2525);
FORCEPROP 1 LAST PART_NUMBER CS21002FB06
J 0
(-14150 2575);
DISPLAY 0.723404 (-14150 2575);
PAINT WHITE (-14150 2575);
FORCEPROP 1 LAST PACK_TYPE 0402LF
J 0
(-14150 2675);
DISPLAY 0.723404 (-14150 2675);
PAINT SKYBLUE (-14150 2675);
FORCEPROP 1 LAST TOLERANCE 1%
J 0
(-14150 2725);
DISPLAY 0.723404 (-14150 2725);
PAINT SKYBLUE (-14150 2725);
FORCEPROP 1 LAST VALUE 1K
J 0
(-14150 2775);
DISPLAY 0.723404 (-14150 2775);
PAINT SKYBLUE (-14150 2775);
FORCEPROP 2 LAST CDS_LIB pure_quanta
J 0
(-14225 2675);
DISPLAY INVISIBLE (-14225 2675);
FORCEPROP 1 LAST PATH I34
R 1
J 0
(-14375 2625);
DISPLAY 0.978723 (-14375 2625);
PAINT WHITE (-14375 2625);
DISPLAY INVISIBLE (-14375 2625);
FORCEADD UNIVERSAL_POWER..1
(-14225 2850);
FORCEPROP 3 LASTPIN (-14225 2800) SIG_NAME P3V3_AUX\g
J 0
(-14215 2810);
DISPLAY 0.659574 (-14215 2810);
PAINT MONO (-14215 2810);
DISPLAY INVISIBLE (-14215 2810);
FORCEPROP 1 LAST HDL_POWER P3V3_AUX
J 1
(-14225 2900);
DISPLAY 0.723404 (-14225 2900);
PAINT GREEN (-14225 2900);
FORCEPROP 2 LAST CDS_LIB pure_quanta_power
J 0
(-14225 2850);
DISPLAY INVISIBLE (-14225 2850);
FORCEPROP 1 LAST PATH I35
J 0
(-14175 2875);
DISPLAY 0.872340 (-14175 2875);
PAINT AQUA (-14175 2875);
DISPLAY INVISIBLE (-14175 2875);
FORCEADD Q_RES..1
(-13675 3075);
FORCEPROP 1 LAST LOCATION R1714
J 0
(-13950 3075);
DISPLAY 0.723404 (-13950 3075);
PAINT AQUA (-13950 3075);
FORCEPROP 0 LAST $SEC 1
J 0
(-13775 3150);
DISPLAY INVISIBLE (-13775 3150);
FORCEPROP 0 LAST CDS_SEC 1
J 0
(-13775 3150);
DISPLAY INVISIBLE (-13775 3150);
FORCEPROP 1 LASTPIN (-13775 3075) $PN 1
J 0
(-13763 3087);
DISPLAY 0.787234 (-13763 3087);
DISPLAY INVISIBLE (-13763 3087);
FORCEPROP 1 LASTPIN (-13575 3075) $PN 2
J 0
(-13613 3087);
DISPLAY 0.787234 (-13613 3087);
DISPLAY INVISIBLE (-13613 3087);
FORCEPROP 1 LAST MATERIAL CHIP
J 0
(-13250 3025);
DISPLAY 0.723404 (-13250 3025);
PAINT SKYBLUE (-13250 3025);
FORCEPROP 1 LAST TOLERANCE 5%
J 0
(-13600 3025);
DISPLAY 0.723404 (-13600 3025);
PAINT SKYBLUE (-13600 3025);
FORCEPROP 1 LAST WATTAGE 1/16W
J 2
(-13275 3075);
DISPLAY 0.723404 (-13275 3075);
PAINT SKYBLUE (-13275 3075);
FORCEPROP 1 LAST VALUE 0
J 2
(-13525 3075);
DISPLAY 0.723404 (-13525 3075);
PAINT SKYBLUE (-13525 3075);
FORCEPROP 1 LAST PACK_TYPE 0402LF
J 0
(-13475 3025);
DISPLAY 0.723404 (-13475 3025);
PAINT SKYBLUE (-13475 3025);
FORCEPROP 1 LAST PART_NUMBER CS00002JB13
J 0
(-14000 3025);
DISPLAY 0.723404 (-14000 3025);
PAINT WHITE (-14000 3025);
FORCEPROP 2 LAST CDS_LIB pure_quanta
J 0
(-13675 3075);
PAINT MONO (-13675 3075);
DISPLAY INVISIBLE (-13675 3075);
FORCEPROP 1 LAST PATH I36
J 0
(-13725 3225);
DISPLAY 0.978723 (-13725 3225);
PAINT WHITE (-13725 3225);
DISPLAY INVISIBLE (-13725 3225);
FORCEADD Q_RES..1
(-13675 3175);
FORCEPROP 1 LAST LOCATION R3909
J 0
(-13950 3175);
DISPLAY 0.638298 (-13950 3175);
FORCEPROP 0 LAST $SEC 1
J 0
(-13475 3325);
DISPLAY 0.680851 (-13475 3325);
PAINT MONO (-13475 3325);
DISPLAY INVISIBLE (-13475 3325);
FORCEPROP 0 LAST CDS_SEC 1
J 0
(-13475 3325);
DISPLAY 1.021277 (-13475 3325);
DISPLAY INVISIBLE (-13475 3325);
FORCEPROP 1 LASTPIN (-13775 3175) $PN 1
J 0
(-13763 3187);
DISPLAY 0.787234 (-13763 3187);
PAINT MONO (-13763 3187);
FORCEPROP 1 LASTPIN (-13575 3175) $PN 2
J 0
(-13613 3187);
DISPLAY 0.787234 (-13613 3187);
PAINT MONO (-13613 3187);
FORCEPROP 1 LAST MATERIAL CHIP
J 0
(-13375 3175);
DISPLAY 0.510638 (-13375 3175);
FORCEPROP 1 LAST TOLERANCE 1%
J 0
(-13450 3175);
DISPLAY 0.510638 (-13450 3175);
FORCEPROP 1 LAST VALUE 33.2
J 2
(-13475 3175);
DISPLAY 0.510638 (-13475 3175);
FORCEPROP 1 LAST PACK_TYPE 0402LF
J 0
(-13775 3300);
DISPLAY 0.510638 (-13775 3300);
FORCEPROP 1 LAST WATTAGE 1/16W
J 2
(-13475 3300);
DISPLAY 0.510638 (-13475 3300);
FORCEPROP 1 LAST PART_NUMBER CS03322FB03
J 0
(-13775 3250);
DISPLAY 0.510638 (-13775 3250);
FORCEPROP 2 LAST CDS_LIB pure_quanta
J 0
(-13675 3175);
DISPLAY INVISIBLE (-13675 3175);
FORCEPROP 1 LAST PATH I37
J 0
(-13725 3325);
DISPLAY 0.978723 (-13725 3325);
PAINT WHITE (-13725 3325);
DISPLAY INVISIBLE (-13725 3325);
FORCEADD UNIVERSAL_GND..1
(-13700 3575);
FORCEPROP 3 LASTPIN (-13700 3625) SIG_NAME AGND_HSC\g
J 0
(-13690 3635);
DISPLAY 0.659574 (-13690 3635);
PAINT MONO (-13690 3635);
DISPLAY INVISIBLE (-13690 3635);
FORCEPROP 1 LAST HDL_POWER AGND_HSC
J 1
(-13675 3500);
DISPLAY 0.723404 (-13675 3500);
PAINT GREEN (-13675 3500);
FORCEPROP 2 LAST CDS_LIB pure_quanta_power
J 0
(-13700 3575);
DISPLAY INVISIBLE (-13700 3575);
FORCEPROP 1 LAST PATH I38
J 0
(-13625 3575);
DISPLAY 0.872340 (-13625 3575);
PAINT AQUA (-13625 3575);
DISPLAY INVISIBLE (-13625 3575);
FORCEADD Q_RES..1
R 1
(-15225 4050);
FORCEPROP 1 LAST LOCATION PR2149
J 0
(-15150 4200);
DISPLAY 0.723404 (-15150 4200);
PAINT AQUA (-15150 4200);
FORCEPROP 0 LAST $SEC 1
R 1
J 0
(-15150 4250);
DISPLAY 0.680851 (-15150 4250);
PAINT MONO (-15150 4250);
DISPLAY INVISIBLE (-15150 4250);
FORCEPROP 0 LAST CDS_SEC 1
R 1
J 0
(-15150 4250);
DISPLAY 1.021277 (-15150 4250);
DISPLAY INVISIBLE (-15150 4250);
FORCEPROP 1 LASTPIN (-15225 3950) $PN 1
R 1
J 0
(-15237 3962);
DISPLAY 0.787234 (-15237 3962);
PAINT MONO (-15237 3962);
FORCEPROP 1 LASTPIN (-15225 4150) $PN 2
R 1
J 0
(-15237 4112);
DISPLAY 0.787234 (-15237 4112);
PAINT MONO (-15237 4112);
FORCEPROP 1 LAST WATTAGE 1/16W
J 0
(-15150 4000);
DISPLAY 0.723404 (-15150 4000);
PAINT SKYBLUE (-15150 4000);
FORCEPROP 1 LAST MATERIAL CHIP
J 0
(-15150 3900);
DISPLAY 0.787234 (-15150 3900);
PAINT SKYBLUE (-15150 3900);
FORCEPROP 1 LAST VALUE 0
R 2
J 0
(-15125 4175);
DISPLAY 0.723404 (-15125 4175);
PAINT SKYBLUE (-15125 4175);
FORCEPROP 1 LAST PART_NUMBER CS00002JB13
J 0
(-15150 3950);
DISPLAY 0.723404 (-15150 3950);
PAINT WHITE (-15150 3950);
FORCEPROP 1 LAST TOLERANCE 5%
J 0
(-15150 4100);
DISPLAY 0.723404 (-15150 4100);
PAINT SKYBLUE (-15150 4100);
FORCEPROP 1 LAST PACK_TYPE 0402LF
J 0
(-15150 4050);
DISPLAY 0.723404 (-15150 4050);
PAINT SKYBLUE (-15150 4050);
FORCEPROP 2 LAST CDS_LIB pure_quanta
J 0
(-15225 4050);
DISPLAY INVISIBLE (-15225 4050);
FORCEPROP 1 LAST PATH I39
R 1
J 0
(-15375 4000);
DISPLAY 0.978723 (-15375 4000);
PAINT WHITE (-15375 4000);
DISPLAY INVISIBLE (-15375 4000);
FORCEADD Q_CAP..1
(-15500 -300);
FORCEPROP 1 LAST LOCATION C1797
J 0
(-15425 -200);
DISPLAY 0.978723 (-15425 -200);
FORCEPROP 0 LAST $SEC 1
J 0
(-15450 -150);
DISPLAY 0.680851 (-15450 -150);
PAINT MONO (-15450 -150);
DISPLAY INVISIBLE (-15450 -150);
FORCEPROP 0 LAST CDS_SEC 1
J 0
(-15450 -150);
DISPLAY 1.021277 (-15450 -150);
DISPLAY INVISIBLE (-15450 -150);
FORCEPROP 1 LASTPIN (-15500 -200) $PN 1
J 0
(-15490 -220);
DISPLAY 0.787234 (-15490 -220);
PAINT MONO (-15490 -220);
DISPLAY INVISIBLE (-15490 -220);
FORCEPROP 1 LASTPIN (-15500 -400) $PN 2
J 0
(-15490 -420);
DISPLAY 0.787234 (-15490 -420);
PAINT MONO (-15490 -420);
DISPLAY INVISIBLE (-15490 -420);
FORCEPROP 1 LAST PART_NUMBER CH4104K1B00
J 0
(-15425 -250);
DISPLAY 0.723404 (-15425 -250);
PAINT BLUE (-15425 -250);
FORCEPROP 1 LAST VALUE 0.1UF
J 0
(-15425 -300);
DISPLAY 0.723404 (-15425 -300);
PAINT SKYBLUE (-15425 -300);
FORCEPROP 1 LAST PACK_TYPE 0402
J 0
(-15425 -500);
DISPLAY 0.723404 (-15425 -500);
PAINT SKYBLUE (-15425 -500);
FORCEPROP 1 LAST MATERIAL X7R
J 0
(-15425 -450);
DISPLAY 0.723404 (-15425 -450);
PAINT SKYBLUE (-15425 -450);
FORCEPROP 1 LAST TOLERANCE 10%
J 0
(-15425 -400);
DISPLAY 0.723404 (-15425 -400);
PAINT SKYBLUE (-15425 -400);
FORCEPROP 1 LAST VOLTAGE 25V
J 0
(-15425 -350);
DISPLAY 0.723404 (-15425 -350);
PAINT SKYBLUE (-15425 -350);
FORCEPROP 2 LAST CDS_LIB pure_quanta
J 0
(-15500 -300);
DISPLAY INVISIBLE (-15500 -300);
FORCEPROP 1 LAST PATH I4
J 0
(-15450 -150);
DISPLAY 0.978723 (-15450 -150);
PAINT WHITE (-15450 -150);
DISPLAY INVISIBLE (-15450 -150);
FORCEADD OFFPAGE..5
(-15400 4475);
FORCEPROP 2 LAST $XR0 301 
J 0
(-15655 4475);
DISPLAY 0.638298 (-15655 4475);
PAINT MONO (-15655 4475);
FORCEPROP 2 LAST CDS_LIB standard
J 0
(-15400 4475);
DISPLAY INVISIBLE (-15400 4475);
FORCEPROP 1 LAST OFFPAGE TRUE
J 0
(-15075 4350);
DISPLAY 0.872340 (-15075 4350);
PAINT AQUA (-15075 4350);
DISPLAY INVISIBLE (-15075 4350);
FORCEPROP 1 LAST COMMENT_BODY TRUE
J 0
(-15300 4400);
DISPLAY 1.170213 (-15300 4400);
PAINT GREEN (-15300 4400);
DISPLAY INVISIBLE (-15300 4400);
FORCEPROP 2 LAST PATH I40
J 0
(-15650 4525);
DISPLAY 1.021277 (-15650 4525);
DISPLAY INVISIBLE (-15650 4525);
FORCEADD UNIVERSAL_POWER..1
(-15225 4275);
FORCEPROP 3 LASTPIN (-15225 4225) SIG_NAME HSC_VDD\g
J 0
(-15215 4235);
DISPLAY 0.659574 (-15215 4235);
PAINT MONO (-15215 4235);
DISPLAY INVISIBLE (-15215 4235);
FORCEPROP 1 LAST HDL_POWER HSC_VDD
J 1
(-15225 4325);
DISPLAY 0.723404 (-15225 4325);
PAINT GREEN (-15225 4325);
FORCEPROP 2 LAST ROOM AUX_SW
J 0
(-15225 4375);
DISPLAY 0.617021 (-15225 4375);
FORCEPROP 2 LAST CDS_LIB pure_quanta_power
J 0
(-15225 4275);
DISPLAY INVISIBLE (-15225 4275);
FORCEPROP 2 LAST BOM_COST MIO_VRD_SB
J 0
(-15225 4375);
DISPLAY 0.617021 (-15225 4375);
PAINT PURPLE (-15225 4375);
DISPLAY INVISIBLE (-15225 4375);
FORCEPROP 1 LAST PATH I41
J 0
(-15175 4300);
DISPLAY 0.872340 (-15175 4300);
PAINT AQUA (-15175 4300);
DISPLAY INVISIBLE (-15175 4300);
FORCEADD GND..1
(-14775 4050);
FORCEPROP 3 LASTPIN (-14775 4100) SIG_NAME GND\g
J 0
(-14765 4110);
DISPLAY 0.659574 (-14765 4110);
PAINT MONO (-14765 4110);
DISPLAY INVISIBLE (-14765 4110);
FORCEPROP 2 LAST ROOM VR_DDR1_POWER_STAGE
J 0
(-15000 4125);
FORCEPROP 2 LAST CDS_LIB pure_quanta_power
J 0
(-14775 4050);
DISPLAY INVISIBLE (-14775 4050);
FORCEPROP 1 LAST SIZE 1B
J 0
(-14700 4000);
DISPLAY 0.872340 (-14700 4000);
PAINT AQUA (-14700 4000);
DISPLAY INVISIBLE (-14700 4000);
FORCEPROP 1 LAST HDL_POWER GND
J 0
(-14775 4200);
DISPLAY 1.170213 (-14775 4200);
PAINT GREEN (-14775 4200);
DISPLAY INVISIBLE (-14775 4200);
FORCEPROP 1 LAST PATH I42
J 0
(-14700 4050);
DISPLAY 0.872340 (-14700 4050);
PAINT AQUA (-14700 4050);
DISPLAY INVISIBLE (-14700 4050);
FORCEADD ZENER_AC..1
R 1
(-14775 4275);
FORCEPROP 1 LAST LOCATION PD13
J 0
(-14525 4225);
DISPLAY 0.723404 (-14525 4225);
PAINT AQUA (-14525 4225);
FORCEPROP 0 LAST $SEC 1
R 1
J 0
(-14725 4400);
DISPLAY 0.680851 (-14725 4400);
PAINT MONO (-14725 4400);
DISPLAY INVISIBLE (-14725 4400);
FORCEPROP 0 LAST CDS_SEC 1
R 1
J 0
(-14725 4400);
DISPLAY 1.021277 (-14725 4400);
DISPLAY INVISIBLE (-14725 4400);
FORCEPROP 0 LASTPIN (-14775 4150) $PN A
R 1
J 2
(-14785 4140);
DISPLAY 0.680851 (-14785 4140);
PAINT MONO (-14785 4140);
FORCEPROP 0 LASTPIN (-14775 4400) $PN C
R 1
J 0
(-14785 4410);
DISPLAY 0.680851 (-14785 4410);
PAINT MONO (-14785 4410);
FORCEPROP 1 LAST MATERIAL IC
J 0
(-14475 4125);
DISPLAY 0.723404 (-14475 4125);
PAINT SKYBLUE (-14475 4125);
FORCEPROP 1 LAST PART_NUMBER BC0MDJ14000
J 0
(-14725 4175);
DISPLAY 0.723404 (-14725 4175);
PAINT WHITE (-14725 4175);
FORCEPROP 2 LAST VALUE 5.0SMDJ14A
J 0
(-14725 4275);
DISPLAY 0.723404 (-14725 4275);
PAINT SKYBLUE (-14725 4275);
FORCEPROP 2 LAST PART_TYPE SMLF
J 0
(-14575 4325);
DISPLAY 1.021277 (-14575 4325);
FORCEPROP 2 LAST CDS_LIB pure_quanta
J 0
(-14775 4275);
DISPLAY INVISIBLE (-14775 4275);
FORCEPROP 1 LAST CDS_LMAN_SYM_OUTLINE -75,50,75,-50
R 1
J 0
(-14775 4275);
DISPLAY 0.468085 (-14775 4275);
PAINT GREEN (-14775 4275);
DISPLAY INVISIBLE (-14775 4275);
FORCEPROP 1 LAST NEEDS_NO_SIZE TRUE
R 1
J 0
(-14775 4275);
DISPLAY 0.723404 (-14775 4275);
PAINT GREEN (-14775 4275);
DISPLAY INVISIBLE (-14775 4275);
FORCEPROP 1 LAST PATH I43
R 1
J 0
(-14775 4275);
DISPLAY 0.723404 (-14775 4275);
PAINT GREEN (-14775 4275);
DISPLAY INVISIBLE (-14775 4275);
FORCEADD Q_FUSE..1
R 3
(-14775 4625);
FORCEPROP 1 LAST $LOCATION FS1
J 2
(-14650 4525);
DISPLAY 0.723404 (-14650 4525);
PAINT GREEN (-14650 4525);
FORCEPROP 0 LAST CDS_LOCATION FS1
R 1
J 0
(-14600 4800);
DISPLAY 1.021277 (-14600 4800);
DISPLAY INVISIBLE (-14600 4800);
FORCEPROP 0 LAST $SEC 1
R 1
J 0
(-14600 4800);
DISPLAY 0.680851 (-14600 4800);
PAINT MONO (-14600 4800);
DISPLAY INVISIBLE (-14600 4800);
FORCEPROP 0 LAST CDS_SEC 1
R 1
J 0
(-14600 4800);
DISPLAY 1.021277 (-14600 4800);
DISPLAY INVISIBLE (-14600 4800);
FORCEPROP 0 LASTPIN (-14775 4725) $PN 1
R 1
J 0
(-14785 4735);
DISPLAY 0.680851 (-14785 4735);
PAINT MONO (-14785 4735);
FORCEPROP 0 LASTPIN (-14775 4525) $PN 2
R 1
J 2
(-14785 4515);
DISPLAY 0.680851 (-14785 4515);
PAINT MONO (-14785 4515);
FORCEPROP 1 LAST MATERIAL IC
J 2
(-14600 4750);
DISPLAY 0.723404 (-14600 4750);
PAINT GREEN (-14600 4750);
FORCEPROP 1 LAST PART_NUMBER DKK00XFU000
J 2
(-14300 4700);
DISPLAY 0.723404 (-14300 4700);
PAINT GREEN (-14300 4700);
FORCEPROP 2 LAST VALUE 20A/125V
J 2
(-14300 4650);
DISPLAY 1.021277 (-14300 4650);
FORCEPROP 2 LAST PACK_TYPE SMLF
J 2
(-14500 4575);
DISPLAY 1.021277 (-14500 4575);
FORCEPROP 2 LAST CDS_LIB pure_quanta
R 1
J 2
(-14775 4625);
DISPLAY INVISIBLE (-14775 4625);
FORCEPROP 1 LAST NEEDS_NO_SIZE TRUE
R 1
J 2
(-14775 4625);
DISPLAY 0.468085 (-14775 4625);
PAINT GREEN (-14775 4625);
DISPLAY INVISIBLE (-14775 4625);
FORCEPROP 1 LAST PATH I44
R 1
J 2
(-14830 4600);
DISPLAY 0.723404 (-14830 4600);
PAINT GREEN (-14830 4600);
DISPLAY INVISIBLE (-14830 4600);
FORCEADD UNIVERSAL_POWER..1
(-14775 4950);
FORCEPROP 3 LASTPIN (-14775 4900) SIG_NAME P12V_PSU\g
J 0
(-14765 4910);
DISPLAY 0.659574 (-14765 4910);
PAINT MONO (-14765 4910);
DISPLAY INVISIBLE (-14765 4910);
FORCEPROP 1 LAST HDL_POWER P12V_PSU
J 1
(-14775 5000);
DISPLAY 0.723404 (-14775 5000);
PAINT GREEN (-14775 5000);
FORCEPROP 2 LAST ROOM AUX_SW
J 0
(-14775 5050);
DISPLAY 0.617021 (-14775 5050);
FORCEPROP 2 LAST CDS_LIB pure_quanta_power
J 0
(-14775 4950);
DISPLAY INVISIBLE (-14775 4950);
FORCEPROP 2 LAST BOM_COST MIO_VRD_SB
J 0
(-14775 5050);
DISPLAY 0.617021 (-14775 5050);
PAINT PURPLE (-14775 5050);
DISPLAY INVISIBLE (-14775 5050);
FORCEPROP 1 LAST PATH I45
J 0
(-14725 4975);
DISPLAY 0.872340 (-14725 4975);
PAINT AQUA (-14725 4975);
DISPLAY INVISIBLE (-14725 4975);
FORCEADD Q_CAP..1
(-14225 4350);
FORCEPROP 1 LAST LOCATION PC2188
J 0
(-14175 4450);
DISPLAY 0.723404 (-14175 4450);
PAINT AQUA (-14175 4450);
FORCEPROP 0 LAST $SEC 1
J 0
(-14175 4500);
DISPLAY 0.680851 (-14175 4500);
PAINT MONO (-14175 4500);
DISPLAY INVISIBLE (-14175 4500);
FORCEPROP 0 LAST CDS_SEC 1
J 0
(-14175 4500);
DISPLAY 1.021277 (-14175 4500);
DISPLAY INVISIBLE (-14175 4500);
FORCEPROP 1 LASTPIN (-14225 4450) $PN 1
J 0
(-14215 4430);
DISPLAY 0.787234 (-14215 4430);
PAINT MONO (-14215 4430);
FORCEPROP 1 LASTPIN (-14225 4250) $PN 2
J 0
(-14215 4230);
DISPLAY 0.787234 (-14215 4230);
PAINT MONO (-14215 4230);
FORCEPROP 1 LAST VOLTAGE 25V
J 0
(-14175 4350);
DISPLAY 0.723404 (-14175 4350);
PAINT SKYBLUE (-14175 4350);
FORCEPROP 1 LAST VALUE 1UF
J 0
(-14175 4400);
DISPLAY 0.723404 (-14175 4400);
PAINT SKYBLUE (-14175 4400);
FORCEPROP 1 LAST MATERIAL X6S
J 0
(-14175 4300);
DISPLAY 0.723404 (-14175 4300);
PAINT SKYBLUE (-14175 4300);
FORCEPROP 1 LAST PACK_TYPE C0402
J 0
(-14175 4200);
DISPLAY 0.723404 (-14175 4200);
PAINT SKYBLUE (-14175 4200);
FORCEPROP 1 LAST PART_NUMBER CH5104KEB02
J 0
(-14175 4250);
DISPLAY 0.723404 (-14175 4250);
PAINT WHITE (-14175 4250);
FORCEPROP 2 LAST CDS_LIB pure_quanta
J 0
(-14225 4350);
DISPLAY INVISIBLE (-14225 4350);
FORCEPROP 1 LAST TOLERANCE 10%
J 0
(-14175 4300);
DISPLAY 0.978723 (-14175 4300);
PAINT SKYBLUE (-14175 4300);
DISPLAY INVISIBLE (-14175 4300);
FORCEPROP 1 LAST PATH I46
J 0
(-14175 4500);
DISPLAY 0.978723 (-14175 4500);
PAINT WHITE (-14175 4500);
DISPLAY INVISIBLE (-14175 4500);
FORCEADD Q_RES..2
(-13700 3900);
FORCEPROP 1 LAST LOCATION PR3927
J 0
(-13655 4025);
DISPLAY 0.978723 (-13655 4025);
FORCEPROP 0 LAST $SEC 1
J 0
(-13650 4075);
DISPLAY 0.680851 (-13650 4075);
PAINT MONO (-13650 4075);
DISPLAY INVISIBLE (-13650 4075);
FORCEPROP 0 LAST CDS_SEC 1
J 0
(-13650 4075);
DISPLAY 1.021277 (-13650 4075);
DISPLAY INVISIBLE (-13650 4075);
FORCEPROP 1 LASTPIN (-13700 4000) $PN 1
J 0
(-13695 3962);
DISPLAY 0.787234 (-13695 3962);
PAINT MONO (-13695 3962);
FORCEPROP 1 LASTPIN (-13700 3800) $PN 2
J 0
(-13695 3810);
DISPLAY 0.787234 (-13695 3810);
PAINT MONO (-13695 3810);
FORCEPROP 1 LAST WATTAGE 1/16W
J 0
(-13660 3875);
DISPLAY 0.638298 (-13660 3875);
FORCEPROP 1 LAST MATERIAL CHIP
J 0
(-13660 3825);
DISPLAY 0.638298 (-13660 3825);
FORCEPROP 1 LAST PACK_TYPE 0402LF
J 0
(-13660 3725);
DISPLAY 0.638298 (-13660 3725);
FORCEPROP 1 LAST PART_NUMBER CS24992BB04
J 0
(-13660 3775);
DISPLAY 0.638298 (-13660 3775);
FORCEPROP 1 LAST TOLERANCE 0.1%
J 0
(-13655 3925);
DISPLAY 0.638298 (-13655 3925);
FORCEPROP 1 LAST VALUE 4.99K
J 0
(-13655 3975);
DISPLAY 0.638298 (-13655 3975);
FORCEPROP 2 LAST CDS_LIB pure_quanta
J 0
(-13700 3900);
DISPLAY INVISIBLE (-13700 3900);
FORCEPROP 1 LAST PATH I47
J 0
(-13650 4075);
DISPLAY 0.978723 (-13650 4075);
PAINT WHITE (-13650 4075);
DISPLAY INVISIBLE (-13650 4075);
FORCEADD Q_RES..2
(-13700 4350);
FORCEPROP 1 LAST LOCATION PR3926
J 0
(-13655 4475);
DISPLAY 0.978723 (-13655 4475);
FORCEPROP 0 LAST $SEC 1
J 0
(-13650 4525);
DISPLAY 0.680851 (-13650 4525);
PAINT MONO (-13650 4525);
DISPLAY INVISIBLE (-13650 4525);
FORCEPROP 0 LAST CDS_SEC 1
J 0
(-13650 4525);
DISPLAY 1.021277 (-13650 4525);
DISPLAY INVISIBLE (-13650 4525);
FORCEPROP 1 LASTPIN (-13700 4450) $PN 1
J 0
(-13695 4412);
DISPLAY 0.787234 (-13695 4412);
PAINT MONO (-13695 4412);
FORCEPROP 1 LASTPIN (-13700 4250) $PN 2
J 0
(-13695 4260);
DISPLAY 0.787234 (-13695 4260);
PAINT MONO (-13695 4260);
FORCEPROP 1 LAST MATERIAL CHIP
J 0
(-13660 4275);
DISPLAY 0.787234 (-13660 4275);
FORCEPROP 1 LAST TOLERANCE 0.1%
J 0
(-13655 4375);
DISPLAY 0.787234 (-13655 4375);
FORCEPROP 1 LAST WATTAGE 1/16W
J 0
(-13660 4325);
DISPLAY 0.787234 (-13660 4325);
FORCEPROP 1 LAST PACK_TYPE 0402LF
J 0
(-13660 4175);
DISPLAY 0.787234 (-13660 4175);
FORCEPROP 1 LAST VALUE 75K
J 0
(-13655 4425);
DISPLAY 0.787234 (-13655 4425);
FORCEPROP 1 LAST PART_NUMBER CS37502BB01
J 0
(-13660 4225);
DISPLAY 0.787234 (-13660 4225);
FORCEPROP 2 LAST CDS_LIB pure_quanta
J 0
(-13700 4350);
DISPLAY INVISIBLE (-13700 4350);
FORCEPROP 1 LAST PATH I48
J 0
(-13650 4525);
DISPLAY 0.978723 (-13650 4525);
PAINT WHITE (-13650 4525);
DISPLAY INVISIBLE (-13650 4525);
FORCEADD UNIVERSAL_GND..1
(-13325 1875);
FORCEPROP 3 LASTPIN (-13325 1925) SIG_NAME AGND_HSC\g
J 0
(-13315 1935);
DISPLAY 0.659574 (-13315 1935);
PAINT MONO (-13315 1935);
DISPLAY INVISIBLE (-13315 1935);
FORCEPROP 1 LAST HDL_POWER AGND_HSC
J 1
(-13300 1800);
DISPLAY 0.723404 (-13300 1800);
PAINT GREEN (-13300 1800);
FORCEPROP 2 LAST CDS_LIB pure_quanta_power
J 0
(-13325 1875);
DISPLAY INVISIBLE (-13325 1875);
FORCEPROP 1 LAST PATH I49
J 0
(-13250 1875);
DISPLAY 0.872340 (-13250 1875);
PAINT AQUA (-13250 1875);
DISPLAY INVISIBLE (-13250 1875);
FORCEADD Q_RES..2
(-14800 -250);
FORCEPROP 1 LAST LOCATION R3907
J 0
(-14755 -125);
DISPLAY 0.723404 (-14755 -125);
PAINT AQUA (-14755 -125);
FORCEPROP 0 LAST $SEC 1
J 0
(-14750 -75);
DISPLAY INVISIBLE (-14750 -75);
FORCEPROP 0 LAST CDS_SEC 1
J 0
(-14750 -75);
DISPLAY INVISIBLE (-14750 -75);
FORCEPROP 1 LASTPIN (-14800 -150) $PN 1
J 0
(-14795 -188);
DISPLAY 0.787234 (-14795 -188);
PAINT MONO (-14795 -188);
DISPLAY INVISIBLE (-14795 -188);
FORCEPROP 1 LASTPIN (-14800 -350) $PN 2
J 0
(-14795 -340);
DISPLAY 0.787234 (-14795 -340);
PAINT MONO (-14795 -340);
DISPLAY INVISIBLE (-14795 -340);
FORCEPROP 1 LAST TOLERANCE 1%
J 0
(-14755 -225);
DISPLAY 0.723404 (-14755 -225);
PAINT SKYBLUE (-14755 -225);
FORCEPROP 1 LAST VALUE 33K
J 0
(-14755 -175);
DISPLAY 0.723404 (-14755 -175);
PAINT SKYBLUE (-14755 -175);
FORCEPROP 1 LAST PART_NUMBER CS33302FB00
J 0
(-14750 -325);
DISPLAY 0.723404 (-14750 -325);
PAINT WHITE (-14750 -325);
FORCEPROP 1 LAST PACK_TYPE 0402LF
J 0
(-14750 -375);
DISPLAY 0.723404 (-14750 -375);
PAINT SKYBLUE (-14750 -375);
FORCEPROP 1 LAST WATTAGE 1/16W
J 0
(-14760 -275);
DISPLAY 0.723404 (-14760 -275);
PAINT SKYBLUE (-14760 -275);
FORCEPROP 1 LAST MATERIAL CHIP
J 0
(-14760 -325);
DISPLAY 0.723404 (-14760 -325);
PAINT SKYBLUE (-14760 -325);
DISPLAY INVISIBLE (-14760 -325);
FORCEPROP 2 LAST CDS_LIB pure_quanta
J 0
(-14800 -250);
DISPLAY INVISIBLE (-14800 -250);
FORCEPROP 1 LAST PATH I5
J 0
(-14750 -75);
DISPLAY 0.978723 (-14750 -75);
PAINT WHITE (-14750 -75);
DISPLAY INVISIBLE (-14750 -75);
FORCEADD Q_CAP..1
(-13325 2175);
FORCEPROP 1 LAST $LOCATION PC2103
J 0
(-13275 2275);
DISPLAY 0.723404 (-13275 2275);
PAINT AQUA (-13275 2275);
FORCEPROP 0 LAST CDS_LOCATION PC2103
J 0
(-13275 2325);
DISPLAY 1.021277 (-13275 2325);
DISPLAY INVISIBLE (-13275 2325);
FORCEPROP 0 LAST $SEC 1
J 0
(-13275 2325);
DISPLAY 0.680851 (-13275 2325);
PAINT MONO (-13275 2325);
DISPLAY INVISIBLE (-13275 2325);
FORCEPROP 0 LAST CDS_SEC 1
J 0
(-13275 2325);
DISPLAY 1.021277 (-13275 2325);
DISPLAY INVISIBLE (-13275 2325);
FORCEPROP 1 LASTPIN (-13325 2275) $PN 1
J 0
(-13315 2255);
DISPLAY 0.787234 (-13315 2255);
PAINT MONO (-13315 2255);
FORCEPROP 1 LASTPIN (-13325 2075) $PN 2
J 0
(-13315 2055);
DISPLAY 0.787234 (-13315 2055);
PAINT MONO (-13315 2055);
FORCEPROP 1 LAST PACK_TYPE C0402
J 0
(-13275 2025);
DISPLAY 0.723404 (-13275 2025);
PAINT SKYBLUE (-13275 2025);
FORCEPROP 1 LAST MATERIAL X6S
J 0
(-13275 2125);
DISPLAY 0.723404 (-13275 2125);
PAINT SKYBLUE (-13275 2125);
FORCEPROP 1 LAST VALUE 1UF
J 0
(-13275 2225);
DISPLAY 0.723404 (-13275 2225);
PAINT SKYBLUE (-13275 2225);
FORCEPROP 1 LAST VOLTAGE 25V
J 0
(-13275 2175);
DISPLAY 0.723404 (-13275 2175);
PAINT SKYBLUE (-13275 2175);
FORCEPROP 1 LAST PART_NUMBER CH5104KEB02
J 0
(-13275 2075);
DISPLAY 0.723404 (-13275 2075);
PAINT WHITE (-13275 2075);
FORCEPROP 2 LAST CDS_LIB pure_quanta
J 0
(-13325 2175);
DISPLAY INVISIBLE (-13325 2175);
FORCEPROP 1 LAST TOLERANCE 10%
J 0
(-13275 2125);
DISPLAY 0.978723 (-13275 2125);
PAINT SKYBLUE (-13275 2125);
DISPLAY INVISIBLE (-13275 2125);
FORCEPROP 1 LAST PATH I50
J 0
(-13275 2325);
DISPLAY 0.978723 (-13275 2325);
PAINT WHITE (-13275 2325);
DISPLAY INVISIBLE (-13275 2325);
FORCEADD Q_RES..1
(-13100 2525);
FORCEPROP 1 LAST LOCATION PR3928
J 0
(-13425 2525);
DISPLAY 0.723404 (-13425 2525);
PAINT AQUA (-13425 2525);
FORCEPROP 0 LAST $SEC 1
J 0
(-12700 2575);
DISPLAY 0.680851 (-12700 2575);
PAINT MONO (-12700 2575);
DISPLAY INVISIBLE (-12700 2575);
FORCEPROP 0 LAST CDS_SEC 1
J 0
(-12700 2575);
DISPLAY 1.021277 (-12700 2575);
DISPLAY INVISIBLE (-12700 2575);
FORCEPROP 1 LASTPIN (-13200 2525) $PN 1
J 0
(-13188 2537);
DISPLAY 0.787234 (-13188 2537);
PAINT MONO (-13188 2537);
FORCEPROP 1 LASTPIN (-13000 2525) $PN 2
J 0
(-13038 2537);
DISPLAY 0.787234 (-13038 2537);
PAINT MONO (-13038 2537);
FORCEPROP 1 LAST PACK_TYPE 0402LF
J 0
(-12925 2475);
DISPLAY 0.723404 (-12925 2475);
PAINT SKYBLUE (-12925 2475);
FORCEPROP 1 LAST TOLERANCE 5%
J 0
(-13025 2475);
DISPLAY 0.723404 (-13025 2475);
PAINT SKYBLUE (-13025 2475);
FORCEPROP 1 LAST VALUE 0
J 2
(-12950 2525);
DISPLAY 0.723404 (-12950 2525);
PAINT SKYBLUE (-12950 2525);
FORCEPROP 1 LAST PART_NUMBER CS00002JB13
J 0
(-13425 2475);
DISPLAY 0.723404 (-13425 2475);
PAINT WHITE (-13425 2475);
FORCEPROP 1 LAST WATTAGE 1/16W
J 2
(-12700 2525);
DISPLAY 0.723404 (-12700 2525);
PAINT SKYBLUE (-12700 2525);
FORCEPROP 1 LAST MATERIAL CHIP
J 0
(-12700 2475);
DISPLAY 0.723404 (-12700 2475);
PAINT SKYBLUE (-12700 2475);
FORCEPROP 2 LAST CDS_LIB pure_quanta
J 0
(-13100 2525);
DISPLAY INVISIBLE (-13100 2525);
FORCEPROP 1 LAST PATH I51
J 0
(-13150 2675);
DISPLAY 0.978723 (-13150 2675);
PAINT WHITE (-13150 2675);
DISPLAY INVISIBLE (-13150 2675);
FORCEADD Q_RES..1
R 1
(-12850 1750);
FORCEPROP 1 LAST LOCATION PR3930
J 0
(-12775 1875);
DISPLAY 0.723404 (-12775 1875);
PAINT AQUA (-12775 1875);
FORCEPROP 0 LAST $SEC 1
R 1
J 0
(-12775 1925);
DISPLAY 0.680851 (-12775 1925);
PAINT MONO (-12775 1925);
DISPLAY INVISIBLE (-12775 1925);
FORCEPROP 0 LAST CDS_SEC 1
R 1
J 0
(-12775 1925);
DISPLAY 1.021277 (-12775 1925);
DISPLAY INVISIBLE (-12775 1925);
FORCEPROP 1 LASTPIN (-12850 1650) $PN 1
R 1
J 0
(-12862 1662);
DISPLAY 0.787234 (-12862 1662);
PAINT MONO (-12862 1662);
FORCEPROP 1 LASTPIN (-12850 1850) $PN 2
R 1
J 0
(-12862 1812);
DISPLAY 0.787234 (-12862 1812);
PAINT MONO (-12862 1812);
FORCEPROP 1 LAST VALUE 0
J 0
(-12775 1825);
DISPLAY 0.723404 (-12775 1825);
PAINT SKYBLUE (-12775 1825);
FORCEPROP 1 LAST TOLERANCE 5%
J 0
(-12775 1775);
DISPLAY 0.723404 (-12775 1775);
PAINT SKYBLUE (-12775 1775);
FORCEPROP 1 LAST PACK_TYPE 0402LF
J 0
(-12775 1725);
DISPLAY 0.723404 (-12775 1725);
PAINT SKYBLUE (-12775 1725);
FORCEPROP 1 LAST WATTAGE 1/16W
J 0
(-12775 1675);
DISPLAY 0.723404 (-12775 1675);
PAINT SKYBLUE (-12775 1675);
FORCEPROP 1 LAST PART_NUMBER CS00002JB13
J 0
(-12775 1625);
DISPLAY 0.723404 (-12775 1625);
PAINT WHITE (-12775 1625);
FORCEPROP 1 LAST MATERIAL CHIP
J 0
(-12775 1575);
DISPLAY 0.808511 (-12775 1575);
PAINT SKYBLUE (-12775 1575);
FORCEPROP 2 LAST CDS_LIB pure_quanta
J 0
(-12850 1750);
DISPLAY INVISIBLE (-12850 1750);
FORCEPROP 1 LAST PATH I52
R 1
J 0
(-13000 1700);
DISPLAY 0.978723 (-13000 1700);
PAINT WHITE (-13000 1700);
DISPLAY INVISIBLE (-13000 1700);
FORCEADD Q_RES..1
R 1
(-12850 2150);
FORCEPROP 1 LAST LOCATION PR3929
J 0
(-12775 2300);
DISPLAY 0.723404 (-12775 2300);
PAINT AQUA (-12775 2300);
FORCEPROP 0 LAST $SEC 1
R 1
J 0
(-12775 2350);
DISPLAY 0.680851 (-12775 2350);
PAINT MONO (-12775 2350);
DISPLAY INVISIBLE (-12775 2350);
FORCEPROP 0 LAST CDS_SEC 1
R 1
J 0
(-12775 2350);
DISPLAY 1.021277 (-12775 2350);
DISPLAY INVISIBLE (-12775 2350);
FORCEPROP 1 LASTPIN (-12850 2050) $PN 1
R 1
J 0
(-12862 2062);
DISPLAY 0.787234 (-12862 2062);
PAINT MONO (-12862 2062);
FORCEPROP 1 LASTPIN (-12850 2250) $PN 2
R 1
J 0
(-12862 2212);
DISPLAY 0.787234 (-12862 2212);
PAINT MONO (-12862 2212);
FORCEPROP 1 LAST MATERIAL EMPTY
J 0
(-12775 2000);
DISPLAY 0.638298 (-12775 2000);
PAINT RED (-12775 2000);
FORCEPROP 1 LAST PART_NUMBER CS21002FB06
J 0
(-12775 2050);
DISPLAY 0.723404 (-12775 2050);
PAINT WHITE (-12775 2050);
FORCEPROP 1 LAST VALUE 1K
J 0
(-12775 2250);
DISPLAY 0.723404 (-12775 2250);
PAINT SKYBLUE (-12775 2250);
FORCEPROP 1 LAST TOLERANCE 1%
J 0
(-12775 2200);
DISPLAY 0.723404 (-12775 2200);
PAINT SKYBLUE (-12775 2200);
FORCEPROP 1 LAST PACK_TYPE 0402LF
J 0
(-12775 2150);
DISPLAY 0.723404 (-12775 2150);
PAINT SKYBLUE (-12775 2150);
FORCEPROP 1 LAST WATTAGE 1/16W
J 0
(-12775 2100);
DISPLAY 0.723404 (-12775 2100);
PAINT SKYBLUE (-12775 2100);
FORCEPROP 2 LAST CDS_LIB pure_quanta
J 0
(-12850 2150);
DISPLAY INVISIBLE (-12850 2150);
FORCEPROP 1 LAST PATH I53
R 1
J 0
(-13000 2100);
DISPLAY 0.978723 (-13000 2100);
PAINT WHITE (-13000 2100);
DISPLAY INVISIBLE (-13000 2100);
FORCEADD Q_RES..1
(-13100 2650);
FORCEPROP 1 LAST LOCATION R2586
J 0
(-13425 2650);
DISPLAY 0.723404 (-13425 2650);
PAINT AQUA (-13425 2650);
FORCEPROP 0 LAST $SEC 1
J 0
(-12700 2700);
DISPLAY 0.680851 (-12700 2700);
PAINT MONO (-12700 2700);
DISPLAY INVISIBLE (-12700 2700);
FORCEPROP 0 LAST CDS_SEC 1
J 0
(-12700 2700);
DISPLAY 1.021277 (-12700 2700);
DISPLAY INVISIBLE (-12700 2700);
FORCEPROP 1 LASTPIN (-13200 2650) $PN 1
J 0
(-13188 2662);
DISPLAY 0.787234 (-13188 2662);
PAINT MONO (-13188 2662);
FORCEPROP 1 LASTPIN (-13000 2650) $PN 2
J 0
(-13038 2662);
DISPLAY 0.787234 (-13038 2662);
PAINT MONO (-13038 2662);
FORCEPROP 1 LAST WATTAGE 1/16W
J 2
(-12700 2650);
DISPLAY 0.723404 (-12700 2650);
PAINT SKYBLUE (-12700 2650);
FORCEPROP 1 LAST VALUE 0
J 2
(-12950 2650);
DISPLAY 0.723404 (-12950 2650);
PAINT SKYBLUE (-12950 2650);
FORCEPROP 1 LAST MATERIAL CHIP
J 0
(-12700 2600);
DISPLAY 0.723404 (-12700 2600);
PAINT SKYBLUE (-12700 2600);
FORCEPROP 1 LAST PART_NUMBER CS00002JB13
J 0
(-13425 2600);
DISPLAY 0.723404 (-13425 2600);
PAINT WHITE (-13425 2600);
FORCEPROP 1 LAST TOLERANCE 5%
J 0
(-13025 2600);
DISPLAY 0.723404 (-13025 2600);
PAINT SKYBLUE (-13025 2600);
FORCEPROP 1 LAST PACK_TYPE 0402LF
J 0
(-12925 2600);
DISPLAY 0.723404 (-12925 2600);
PAINT SKYBLUE (-12925 2600);
FORCEPROP 2 LAST CDS_LIB pure_quanta
J 0
(-13100 2650);
DISPLAY INVISIBLE (-13100 2650);
FORCEPROP 1 LAST PATH I54
J 0
(-13150 2800);
DISPLAY 0.978723 (-13150 2800);
PAINT WHITE (-13150 2800);
DISPLAY INVISIBLE (-13150 2800);
FORCEADD UNIVERSAL_POWER..1
(-13600 2850);
FORCEPROP 3 LASTPIN (-13600 2800) SIG_NAME HSC_VDD\g
J 0
(-13590 2810);
DISPLAY 0.659574 (-13590 2810);
PAINT MONO (-13590 2810);
DISPLAY INVISIBLE (-13590 2810);
FORCEPROP 1 LAST HDL_POWER HSC_VDD
J 1
(-13600 2900);
DISPLAY 0.723404 (-13600 2900);
PAINT GREEN (-13600 2900);
FORCEPROP 2 LAST ROOM AUX_SW
J 0
(-13600 2950);
DISPLAY 0.617021 (-13600 2950);
FORCEPROP 2 LAST BOM_COST MIO_VRD_SB
J 0
(-13600 2950);
DISPLAY 0.617021 (-13600 2950);
PAINT PURPLE (-13600 2950);
DISPLAY INVISIBLE (-13600 2950);
FORCEPROP 2 LAST CDS_LIB pure_quanta_power
J 0
(-13600 2850);
DISPLAY INVISIBLE (-13600 2850);
FORCEPROP 1 LAST PATH I55
J 0
(-13550 2875);
DISPLAY 0.872340 (-13550 2875);
PAINT AQUA (-13550 2875);
DISPLAY INVISIBLE (-13550 2875);
FORCEADD Q_RES..1
(-13100 2775);
FORCEPROP 1 LAST $LOCATION PR2106
J 0
(-13425 2775);
DISPLAY 0.723404 (-13425 2775);
PAINT AQUA (-13425 2775);
FORCEPROP 0 LAST CDS_LOCATION PR2106
J 0
(-12700 2825);
DISPLAY 1.021277 (-12700 2825);
DISPLAY INVISIBLE (-12700 2825);
FORCEPROP 0 LAST $SEC 1
J 0
(-12700 2825);
DISPLAY 0.680851 (-12700 2825);
PAINT MONO (-12700 2825);
DISPLAY INVISIBLE (-12700 2825);
FORCEPROP 0 LAST CDS_SEC 1
J 0
(-12700 2825);
DISPLAY 1.021277 (-12700 2825);
DISPLAY INVISIBLE (-12700 2825);
FORCEPROP 1 LASTPIN (-13200 2775) $PN 1
J 0
(-13188 2787);
DISPLAY 0.787234 (-13188 2787);
PAINT MONO (-13188 2787);
FORCEPROP 1 LASTPIN (-13000 2775) $PN 2
J 0
(-13038 2787);
DISPLAY 0.787234 (-13038 2787);
PAINT MONO (-13038 2787);
FORCEPROP 1 LAST WATTAGE 1/16W
J 2
(-12700 2775);
DISPLAY 0.723404 (-12700 2775);
PAINT SKYBLUE (-12700 2775);
FORCEPROP 1 LAST PACK_TYPE 0402LF
J 0
(-12925 2725);
DISPLAY 0.723404 (-12925 2725);
PAINT SKYBLUE (-12925 2725);
FORCEPROP 1 LAST VALUE 10K
J 2
(-12925 2775);
DISPLAY 0.723404 (-12925 2775);
PAINT SKYBLUE (-12925 2775);
FORCEPROP 1 LAST PART_NUMBER CS31002FB08
J 0
(-13425 2725);
DISPLAY 0.723404 (-13425 2725);
PAINT WHITE (-13425 2725);
FORCEPROP 1 LAST TOLERANCE 1%
J 0
(-13025 2725);
DISPLAY 0.723404 (-13025 2725);
PAINT SKYBLUE (-13025 2725);
FORCEPROP 1 LAST MATERIAL CHIP
J 0
(-12700 2725);
DISPLAY 0.723404 (-12700 2725);
PAINT SKYBLUE (-12700 2725);
FORCEPROP 2 LAST CDS_LIB pure_quanta
J 0
(-13100 2775);
DISPLAY INVISIBLE (-13100 2775);
FORCEPROP 1 LAST PATH I56
J 0
(-13150 2925);
DISPLAY 0.978723 (-13150 2925);
PAINT WHITE (-13150 2925);
DISPLAY INVISIBLE (-13150 2925);
FORCEADD UNIVERSAL_GND..1
(-12075 1925);
FORCEPROP 3 LASTPIN (-12075 1975) SIG_NAME AGND_HSC\g
J 0
(-12065 1985);
DISPLAY 0.659574 (-12065 1985);
PAINT MONO (-12065 1985);
DISPLAY INVISIBLE (-12065 1985);
FORCEPROP 1 LAST HDL_POWER AGND_HSC
J 1
(-12050 1850);
DISPLAY 0.723404 (-12050 1850);
PAINT GREEN (-12050 1850);
FORCEPROP 2 LAST CDS_LIB pure_quanta_power
J 0
(-12075 1925);
DISPLAY INVISIBLE (-12075 1925);
FORCEPROP 1 LAST PATH I57
J 0
(-12000 1925);
DISPLAY 0.872340 (-12000 1925);
PAINT AQUA (-12000 1925);
DISPLAY INVISIBLE (-12000 1925);
FORCEADD MP5990GMA1111Z..1
(-11400 3050);
FORCEPROP 1 LAST LOCATION PU289
J 0
(-11800 4350);
DISPLAY 0.723404 (-11800 4350);
PAINT GREEN (-11800 4350);
FORCEPROP 0 LAST $SEC 1
J 0
(-11800 4500);
DISPLAY 0.680851 (-11800 4500);
PAINT MONO (-11800 4500);
DISPLAY INVISIBLE (-11800 4500);
FORCEPROP 0 LAST CDS_SEC 1
J 0
(-11800 4500);
DISPLAY 1.021277 (-11800 4500);
DISPLAY INVISIBLE (-11800 4500);
FORCEPROP 0 LASTPIN (-11975 2225) $PN 23
J 2
(-11985 2235);
DISPLAY 0.680851 (-11985 2235);
PAINT MONO (-11985 2235);
FORCEPROP 0 LASTPIN (-11975 2975) $PN 10
J 2
(-11985 2985);
DISPLAY 0.680851 (-11985 2985);
PAINT MONO (-11985 2985);
FORCEPROP 0 LASTPIN (-10825 2975) $PN 20
J 0
(-10815 2985);
DISPLAY 0.680851 (-10815 2985);
PAINT MONO (-10815 2985);
FORCEPROP 0 LASTPIN (-10825 3275) $PN 37
J 0
(-10815 3285);
DISPLAY 0.680851 (-10815 3285);
PAINT MONO (-10815 3285);
FORCEPROP 0 LASTPIN (-11975 2775) $PN 26
J 2
(-11985 2785);
DISPLAY 0.680851 (-11985 2785);
PAINT MONO (-11985 2785);
FORCEPROP 0 LASTPIN (-10825 2275) $PN 40
J 0
(-10815 2285);
DISPLAY 0.680851 (-10815 2285);
PAINT MONO (-10815 2285);
FORCEPROP 0 LASTPIN (-11975 2075) $PN 18
J 2
(-11985 2085);
DISPLAY 0.680851 (-11985 2085);
PAINT MONO (-11985 2085);
FORCEPROP 0 LASTPIN (-11975 2025) $PN 44
J 2
(-11985 2035);
DISPLAY 0.680851 (-11985 2035);
PAINT MONO (-11985 2035);
FORCEPROP 0 LASTPIN (-10825 3375) $PN 39
J 0
(-10815 3385);
DISPLAY 0.680851 (-10815 3385);
PAINT MONO (-10815 3385);
FORCEPROP 0 LASTPIN (-10825 3075) $PN 21
J 0
(-10815 3085);
DISPLAY 0.680851 (-10815 3085);
PAINT MONO (-10815 3085);
FORCEPROP 0 LASTPIN (-10825 3175) $PN 41
J 0
(-10815 3185);
DISPLAY 0.680851 (-10815 3185);
PAINT MONO (-10815 3185);
FORCEPROP 0 LASTPIN (-10825 2575) $PN 22
J 0
(-10815 2585);
DISPLAY 0.680851 (-10815 2585);
PAINT MONO (-10815 2585);
FORCEPROP 0 LASTPIN (-11975 2525) $PN 38
J 2
(-11985 2535);
DISPLAY 0.680851 (-11985 2535);
PAINT MONO (-11985 2535);
FORCEPROP 0 LASTPIN (-10825 2075) $PN 13
J 0
(-10815 2085);
DISPLAY 0.680851 (-10815 2085);
PAINT MONO (-10815 2085);
FORCEPROP 0 LASTPIN (-11975 3175) $PN 11
J 2
(-11985 3185);
DISPLAY 0.680851 (-11985 3185);
PAINT MONO (-11985 3185);
FORCEPROP 0 LASTPIN (-10825 2475) $PN 25
J 0
(-10815 2485);
DISPLAY 0.680851 (-10815 2485);
PAINT MONO (-10815 2485);
FORCEPROP 0 LASTPIN (-11975 3075) $PN 12
J 2
(-11985 3085);
DISPLAY 0.680851 (-11985 3085);
PAINT MONO (-11985 3085);
FORCEPROP 0 LASTPIN (-10825 2375) $PN 16
J 0
(-10815 2385);
DISPLAY 0.680851 (-10815 2385);
PAINT MONO (-10815 2385);
FORCEPROP 0 LASTPIN (-11975 2375) $PN 19
J 2
(-11985 2385);
DISPLAY 0.680851 (-11985 2385);
PAINT MONO (-11985 2385);
FORCEPROP 0 LASTPIN (-11975 3375) $PN 17
J 2
(-11985 3385);
DISPLAY 0.680851 (-11985 3385);
PAINT MONO (-11985 3385);
FORCEPROP 0 LASTPIN (-11975 3325) $PN 45
J 2
(-11985 3335);
DISPLAY 0.680851 (-11985 3335);
PAINT MONO (-11985 3335);
FORCEPROP 0 LASTPIN (-11975 4125) $PN 1
J 2
(-11985 4135);
DISPLAY 0.680851 (-11985 4135);
PAINT MONO (-11985 4135);
FORCEPROP 0 LASTPIN (-11975 4075) $PN 2
J 2
(-11985 4085);
DISPLAY 0.680851 (-11985 4085);
PAINT MONO (-11985 4085);
FORCEPROP 0 LASTPIN (-11975 4025) $PN 3
J 2
(-11985 4035);
DISPLAY 0.680851 (-11985 4035);
PAINT MONO (-11985 4035);
FORCEPROP 0 LASTPIN (-11975 3975) $PN 4
J 2
(-11985 3985);
DISPLAY 0.680851 (-11985 3985);
PAINT MONO (-11985 3985);
FORCEPROP 0 LASTPIN (-11975 3925) $PN 5
J 2
(-11985 3935);
DISPLAY 0.680851 (-11985 3935);
PAINT MONO (-11985 3935);
FORCEPROP 0 LASTPIN (-11975 3875) $PN 6
J 2
(-11985 3885);
DISPLAY 0.680851 (-11985 3885);
PAINT MONO (-11985 3885);
FORCEPROP 0 LASTPIN (-11975 3825) $PN 7
J 2
(-11985 3835);
DISPLAY 0.680851 (-11985 3835);
PAINT MONO (-11985 3835);
FORCEPROP 0 LASTPIN (-11975 3775) $PN 8
J 2
(-11985 3785);
DISPLAY 0.680851 (-11985 3785);
PAINT MONO (-11985 3785);
FORCEPROP 0 LASTPIN (-11975 3725) $PN 42
J 2
(-11985 3735);
DISPLAY 0.680851 (-11985 3735);
PAINT MONO (-11985 3735);
FORCEPROP 0 LASTPIN (-11975 3675) $PN 43
J 2
(-11985 3685);
DISPLAY 0.680851 (-11985 3685);
PAINT MONO (-11985 3685);
FORCEPROP 0 LASTPIN (-11975 2875) $PN 14
J 2
(-11985 2885);
DISPLAY 0.680851 (-11985 2885);
PAINT MONO (-11985 2885);
FORCEPROP 0 LASTPIN (-11975 3575) $PN 9
J 2
(-11985 3585);
DISPLAY 0.680851 (-11985 3585);
PAINT MONO (-11985 3585);
FORCEPROP 0 LASTPIN (-10825 3575) $PN 24
J 0
(-10815 3585);
DISPLAY 0.680851 (-10815 3585);
PAINT MONO (-10815 3585);
FORCEPROP 0 LASTPIN (-10825 4125) $PN 27
J 0
(-10815 4135);
DISPLAY 0.680851 (-10815 4135);
PAINT MONO (-10815 4135);
FORCEPROP 0 LASTPIN (-10825 4075) $PN 28
J 0
(-10815 4085);
DISPLAY 0.680851 (-10815 4085);
PAINT MONO (-10815 4085);
FORCEPROP 0 LASTPIN (-10825 4025) $PN 29
J 0
(-10815 4035);
DISPLAY 0.680851 (-10815 4035);
PAINT MONO (-10815 4035);
FORCEPROP 0 LASTPIN (-10825 3975) $PN 30
J 0
(-10815 3985);
DISPLAY 0.680851 (-10815 3985);
PAINT MONO (-10815 3985);
FORCEPROP 0 LASTPIN (-10825 3925) $PN 31
J 0
(-10815 3935);
DISPLAY 0.680851 (-10815 3935);
PAINT MONO (-10815 3935);
FORCEPROP 0 LASTPIN (-10825 3875) $PN 32
J 0
(-10815 3885);
DISPLAY 0.680851 (-10815 3885);
PAINT MONO (-10815 3885);
FORCEPROP 0 LASTPIN (-10825 3825) $PN 33
J 0
(-10815 3835);
DISPLAY 0.680851 (-10815 3835);
PAINT MONO (-10815 3835);
FORCEPROP 0 LASTPIN (-10825 3775) $PN 34
J 0
(-10815 3785);
DISPLAY 0.680851 (-10815 3785);
PAINT MONO (-10815 3785);
FORCEPROP 0 LASTPIN (-10825 3725) $PN 35
J 0
(-10815 3735);
DISPLAY 0.680851 (-10815 3735);
PAINT MONO (-10815 3735);
FORCEPROP 0 LASTPIN (-10825 3675) $PN 36
J 0
(-10815 3685);
DISPLAY 0.680851 (-10815 3685);
PAINT MONO (-10815 3685);
FORCEPROP 0 LASTPIN (-10825 2675) $PN 15
J 0
(-10815 2685);
DISPLAY 0.680851 (-10815 2685);
PAINT MONO (-10815 2685);
FORCEPROP 1 LAST MATERIAL IC
J 0
(-11820 4187);
DISPLAY 0.723404 (-11820 4187);
PAINT GREEN (-11820 4187);
FORCEPROP 1 LAST PART_NUMBER AL005990A03
J 0
(-11800 4300);
DISPLAY 0.723404 (-11800 4300);
PAINT GREEN (-11800 4300);
FORCEPROP 2 LAST VALUE MP5990GMA-1111-Z
J 0
(-11800 4400);
DISPLAY 1.021277 (-11800 4400);
FORCEPROP 2 LAST PART_TYPE SMLF
J 0
(-11800 4450);
DISPLAY 1.021277 (-11800 4450);
FORCEPROP 2 LASTPIN (-10825 3575) SIG_NAME HSC_VOSEN
J 0
(-10710 3585);
DISPLAY 0.808511 (-10710 3585);
FORCEPROP 1 LAST CDS_LMAN_SYM_OUTLINE -425,1125,425,-1125
J 0
(-11400 3050);
DISPLAY 0.468085 (-11400 3050);
PAINT GREEN (-11400 3050);
DISPLAY INVISIBLE (-11400 3050);
FORCEPROP 1 LAST NEEDS_NO_SIZE TRUE
J 0
(-11400 3050);
DISPLAY 0.723404 (-11400 3050);
PAINT GREEN (-11400 3050);
DISPLAY INVISIBLE (-11400 3050);
FORCEPROP 2 LAST CDS_LIB pure_quanta
J 0
(-11400 3050);
DISPLAY INVISIBLE (-11400 3050);
FORCEPROP 1 LAST PATH I58
J 0
(-11400 3050);
DISPLAY 0.723404 (-11400 3050);
PAINT GREEN (-11400 3050);
DISPLAY INVISIBLE (-11400 3050);
FORCEADD Q_CAP..1
(-13175 3900);
FORCEPROP 1 LAST LOCATION PC2189
J 0
(-13100 3975);
DISPLAY 0.723404 (-13100 3975);
PAINT AQUA (-13100 3975);
FORCEPROP 0 LAST $SEC 1
J 0
(-13100 4100);
DISPLAY 0.680851 (-13100 4100);
PAINT MONO (-13100 4100);
DISPLAY INVISIBLE (-13100 4100);
FORCEPROP 0 LAST CDS_SEC 1
J 0
(-13100 4100);
DISPLAY 1.021277 (-13100 4100);
DISPLAY INVISIBLE (-13100 4100);
FORCEPROP 1 LASTPIN (-13175 4000) $PN 1
J 0
(-13165 3980);
DISPLAY 0.787234 (-13165 3980);
PAINT MONO (-13165 3980);
FORCEPROP 1 LASTPIN (-13175 3800) $PN 2
J 0
(-13165 3780);
DISPLAY 0.787234 (-13165 3780);
PAINT MONO (-13165 3780);
FORCEPROP 1 LAST PART_NUMBER CH31006KB18
J 0
(-13100 3775);
DISPLAY 0.723404 (-13100 3775);
PAINT WHITE (-13100 3775);
FORCEPROP 1 LAST MATERIAL X7R
J 0
(-13100 3825);
DISPLAY 0.723404 (-13100 3825);
PAINT SKYBLUE (-13100 3825);
FORCEPROP 1 LAST VALUE 0.01UF
J 0
(-13100 3925);
DISPLAY 0.723404 (-13100 3925);
PAINT SKYBLUE (-13100 3925);
FORCEPROP 1 LAST PACK_TYPE C0402
J 0
(-13100 3725);
DISPLAY 0.723404 (-13100 3725);
PAINT SKYBLUE (-13100 3725);
FORCEPROP 1 LAST VOLTAGE 50V
J 0
(-13100 3875);
DISPLAY 0.723404 (-13100 3875);
PAINT SKYBLUE (-13100 3875);
FORCEPROP 2 LAST CDS_LIB pure_quanta
J 0
(-13175 3900);
DISPLAY INVISIBLE (-13175 3900);
FORCEPROP 1 LAST TOLERANCE 10%
J 0
(-13125 3850);
DISPLAY 0.978723 (-13125 3850);
PAINT SKYBLUE (-13125 3850);
DISPLAY INVISIBLE (-13125 3850);
FORCEPROP 1 LAST PATH I59
J 0
(-13125 4050);
DISPLAY 0.978723 (-13125 4050);
PAINT WHITE (-13125 4050);
DISPLAY INVISIBLE (-13125 4050);
FORCEADD Q_RES..2
(-14850 250);
FORCEPROP 1 LAST LOCATION R3923
J 0
(-14805 375);
DISPLAY 0.723404 (-14805 375);
PAINT AQUA (-14805 375);
FORCEPROP 0 LAST $SEC 1
J 0
(-14800 425);
DISPLAY 0.680851 (-14800 425);
PAINT MONO (-14800 425);
DISPLAY INVISIBLE (-14800 425);
FORCEPROP 0 LAST CDS_SEC 1
J 0
(-14800 425);
DISPLAY 1.021277 (-14800 425);
DISPLAY INVISIBLE (-14800 425);
FORCEPROP 1 LASTPIN (-14850 350) $PN 1
J 0
(-14845 312);
DISPLAY 0.787234 (-14845 312);
PAINT MONO (-14845 312);
FORCEPROP 1 LASTPIN (-14850 150) $PN 2
J 0
(-14845 160);
DISPLAY 0.787234 (-14845 160);
PAINT MONO (-14845 160);
FORCEPROP 1 LAST WATTAGE 1/16W
J 0
(-14810 225);
DISPLAY 0.723404 (-14810 225);
PAINT SKYBLUE (-14810 225);
FORCEPROP 1 LAST TOLERANCE 1%
J 0
(-14805 275);
DISPLAY 0.723404 (-14805 275);
PAINT SKYBLUE (-14805 275);
FORCEPROP 1 LAST VALUE 63.4K
J 0
(-14805 325);
DISPLAY 0.723404 (-14805 325);
PAINT SKYBLUE (-14805 325);
FORCEPROP 1 LAST PART_NUMBER CS36342FB04
J 0
(-14800 175);
DISPLAY 0.723404 (-14800 175);
PAINT WHITE (-14800 175);
FORCEPROP 1 LAST PACK_TYPE 0402LF
J 0
(-14800 125);
DISPLAY 0.723404 (-14800 125);
PAINT SKYBLUE (-14800 125);
FORCEPROP 2 LAST CDS_LIB pure_quanta
J 0
(-14850 250);
DISPLAY INVISIBLE (-14850 250);
FORCEPROP 1 LAST MATERIAL CHIP
J 0
(-14810 175);
DISPLAY 0.723404 (-14810 175);
PAINT SKYBLUE (-14810 175);
DISPLAY INVISIBLE (-14810 175);
FORCEPROP 1 LAST PATH I6
J 0
(-14800 425);
DISPLAY 0.978723 (-14800 425);
PAINT WHITE (-14800 425);
DISPLAY INVISIBLE (-14800 425);
FORCEADD OFFPAGE..5
R 2
(-10150 2275);
FORCEPROP 2 LAST $XR1 303 
J 0
(-9841 2275);
DISPLAY 0.638298 (-9841 2275);
PAINT MONO (-9841 2275);
FORCEPROP 2 LAST $XR0 302 
J 0
(-9961 2275);
DISPLAY 0.638298 (-9961 2275);
PAINT MONO (-9961 2275);
FORCEPROP 2 LAST CDS_LIB standard
J 0
(-10150 2275);
DISPLAY INVISIBLE (-10150 2275);
FORCEPROP 1 LAST OFFPAGE TRUE
J 2
(-10475 2150);
DISPLAY 0.872340 (-10475 2150);
PAINT AQUA (-10475 2150);
DISPLAY INVISIBLE (-10475 2150);
FORCEPROP 1 LAST COMMENT_BODY TRUE
J 2
(-10250 2200);
DISPLAY 1.170213 (-10250 2200);
PAINT GREEN (-10250 2200);
DISPLAY INVISIBLE (-10250 2200);
FORCEPROP 2 LAST PATH I60
J 0
(-9825 2325);
DISPLAY 1.021277 (-9825 2325);
DISPLAY INVISIBLE (-9825 2325);
FORCEADD OFFPAGE..5
R 2
(-10150 2575);
FORCEPROP 2 LAST $XR1 303 
J 0
(-9841 2575);
DISPLAY 0.638298 (-9841 2575);
PAINT MONO (-9841 2575);
FORCEPROP 2 LAST $XR0 302 
J 0
(-9961 2575);
DISPLAY 0.638298 (-9961 2575);
PAINT MONO (-9961 2575);
FORCEPROP 2 LAST CDS_LIB standard
J 0
(-10150 2575);
DISPLAY INVISIBLE (-10150 2575);
FORCEPROP 1 LAST OFFPAGE TRUE
J 2
(-10475 2450);
DISPLAY 0.872340 (-10475 2450);
PAINT AQUA (-10475 2450);
DISPLAY INVISIBLE (-10475 2450);
FORCEPROP 1 LAST COMMENT_BODY TRUE
J 2
(-10250 2500);
DISPLAY 1.170213 (-10250 2500);
PAINT GREEN (-10250 2500);
DISPLAY INVISIBLE (-10250 2500);
FORCEPROP 2 LAST PATH I61
J 0
(-9825 2625);
DISPLAY 1.021277 (-9825 2625);
DISPLAY INVISIBLE (-9825 2625);
FORCEADD OFFPAGE..5
R 2
(-10150 2475);
FORCEPROP 2 LAST $XR1 303 
J 0
(-9841 2475);
DISPLAY 0.638298 (-9841 2475);
PAINT MONO (-9841 2475);
FORCEPROP 2 LAST $XR0 302 
J 0
(-9961 2475);
DISPLAY 0.638298 (-9961 2475);
PAINT MONO (-9961 2475);
FORCEPROP 2 LAST CDS_LIB standard
J 0
(-10150 2475);
DISPLAY INVISIBLE (-10150 2475);
FORCEPROP 1 LAST OFFPAGE TRUE
J 2
(-10475 2350);
DISPLAY 0.872340 (-10475 2350);
PAINT AQUA (-10475 2350);
DISPLAY INVISIBLE (-10475 2350);
FORCEPROP 1 LAST COMMENT_BODY TRUE
J 2
(-10250 2400);
DISPLAY 1.170213 (-10250 2400);
PAINT GREEN (-10250 2400);
DISPLAY INVISIBLE (-10250 2400);
FORCEPROP 2 LAST PATH I62
J 0
(-9825 2525);
DISPLAY 1.021277 (-9825 2525);
DISPLAY INVISIBLE (-9825 2525);
FORCEADD Q_RES..2
(-9975 1900);
FORCEPROP 1 LAST LOCATION R3933
J 0
(-9930 2025);
DISPLAY 0.723404 (-9930 2025);
PAINT AQUA (-9930 2025);
FORCEPROP 0 LAST $SEC 1
J 0
(-9925 2075);
DISPLAY 0.680851 (-9925 2075);
PAINT MONO (-9925 2075);
DISPLAY INVISIBLE (-9925 2075);
FORCEPROP 0 LAST CDS_SEC 1
J 0
(-9925 2075);
DISPLAY 1.021277 (-9925 2075);
DISPLAY INVISIBLE (-9925 2075);
FORCEPROP 1 LASTPIN (-9975 2000) $PN 1
J 0
(-9970 1962);
DISPLAY 0.787234 (-9970 1962);
PAINT MONO (-9970 1962);
FORCEPROP 1 LASTPIN (-9975 1800) $PN 2
J 0
(-9970 1810);
DISPLAY 0.787234 (-9970 1810);
PAINT MONO (-9970 1810);
FORCEPROP 1 LAST PART_NUMBER CS31692FB03
J 0
(-9935 1775);
DISPLAY 0.723404 (-9935 1775);
PAINT WHITE (-9935 1775);
FORCEPROP 1 LAST TOLERANCE 1%
J 0
(-9930 1925);
DISPLAY 0.723404 (-9930 1925);
PAINT SKYBLUE (-9930 1925);
FORCEPROP 1 LAST PACK_TYPE 0402LF
J 0
(-9935 1725);
DISPLAY 0.723404 (-9935 1725);
PAINT SKYBLUE (-9935 1725);
FORCEPROP 1 LAST MATERIAL CHIP
J 0
(-9935 1825);
DISPLAY 0.723404 (-9935 1825);
PAINT SKYBLUE (-9935 1825);
FORCEPROP 1 LAST VALUE 16.9K
J 0
(-9930 1975);
DISPLAY 0.723404 (-9930 1975);
PAINT SKYBLUE (-9930 1975);
FORCEPROP 1 LAST WATTAGE 1/16W
J 0
(-9935 1875);
DISPLAY 0.723404 (-9935 1875);
PAINT SKYBLUE (-9935 1875);
FORCEPROP 2 LAST CDS_LIB pure_quanta
J 0
(-9975 1900);
DISPLAY INVISIBLE (-9975 1900);
FORCEPROP 1 LAST PATH I63
J 0
(-9925 2075);
DISPLAY 0.978723 (-9925 2075);
PAINT WHITE (-9925 2075);
DISPLAY INVISIBLE (-9925 2075);
FORCEADD UNIVERSAL_POWER..1
(-9975 2100);
FORCEPROP 3 LASTPIN (-9975 2050) SIG_NAME P12V_AUX\g
J 0
(-9965 2060);
DISPLAY 0.659574 (-9965 2060);
PAINT MONO (-9965 2060);
DISPLAY INVISIBLE (-9965 2060);
FORCEPROP 1 LAST HDL_POWER P12V_AUX
J 1
(-9975 2150);
DISPLAY 0.723404 (-9975 2150);
PAINT GREEN (-9975 2150);
FORCEPROP 2 LAST ROOM AUX_SW
J 0
(-9975 2200);
DISPLAY 0.617021 (-9975 2200);
FORCEPROP 2 LAST BOM_COST MIO_VRD_SB
J 0
(-9975 2200);
DISPLAY 0.617021 (-9975 2200);
PAINT PURPLE (-9975 2200);
DISPLAY INVISIBLE (-9975 2200);
FORCEPROP 2 LAST CDS_LIB pure_quanta_power
J 0
(-9975 2100);
DISPLAY INVISIBLE (-9975 2100);
FORCEPROP 1 LAST PATH I64
J 0
(-9925 2125);
DISPLAY 0.872340 (-9925 2125);
PAINT AQUA (-9925 2125);
DISPLAY INVISIBLE (-9925 2125);
FORCEADD Q_RES..1
(-10150 2975);
FORCEPROP 1 LAST $LOCATION PR1131
J 0
(-10425 3000);
DISPLAY 0.723404 (-10425 3000);
PAINT AQUA (-10425 3000);
FORCEPROP 0 LAST CDS_LOCATION PR1131
J 0
(-10100 3050);
DISPLAY 1.021277 (-10100 3050);
DISPLAY INVISIBLE (-10100 3050);
FORCEPROP 0 LAST $SEC 1
J 0
(-10100 3050);
DISPLAY 0.680851 (-10100 3050);
PAINT MONO (-10100 3050);
DISPLAY INVISIBLE (-10100 3050);
FORCEPROP 0 LAST CDS_SEC 1
J 0
(-10100 3050);
DISPLAY 1.021277 (-10100 3050);
DISPLAY INVISIBLE (-10100 3050);
FORCEPROP 1 LASTPIN (-10250 2975) $PN 1
J 0
(-10238 2987);
DISPLAY 0.787234 (-10238 2987);
PAINT MONO (-10238 2987);
FORCEPROP 1 LASTPIN (-10050 2975) $PN 2
J 0
(-10088 2987);
DISPLAY 0.787234 (-10088 2987);
PAINT MONO (-10088 2987);
FORCEPROP 1 LAST PART_NUMBER CS22002BB07
J 0
(-10025 3000);
DISPLAY 0.723404 (-10025 3000);
PAINT WHITE (-10025 3000);
FORCEPROP 1 LAST WATTAGE 1/16W
J 2
(-10225 2875);
DISPLAY 0.723404 (-10225 2875);
PAINT SKYBLUE (-10225 2875);
FORCEPROP 1 LAST MATERIAL CHIP
J 0
(-10200 2875);
DISPLAY 0.723404 (-10200 2875);
PAINT SKYBLUE (-10200 2875);
FORCEPROP 1 LAST PACK_TYPE 0402LF
J 0
(-9975 2875);
DISPLAY 0.723404 (-9975 2875);
PAINT SKYBLUE (-9975 2875);
FORCEPROP 1 LAST VALUE 2K
J 2
(-10200 2925);
DISPLAY 0.723404 (-10200 2925);
PAINT SKYBLUE (-10200 2925);
FORCEPROP 1 LAST TOLERANCE 0.1%
J 0
(-10050 2925);
DISPLAY 0.723404 (-10050 2925);
PAINT SKYBLUE (-10050 2925);
FORCEPROP 2 LAST CDS_LIB pure_quanta
J 0
(-10150 2975);
DISPLAY INVISIBLE (-10150 2975);
FORCEPROP 1 LAST PATH I65
J 0
(-10200 3125);
DISPLAY 0.978723 (-10200 3125);
PAINT WHITE (-10200 3125);
DISPLAY INVISIBLE (-10200 3125);
FORCEADD UNIVERSAL_GND..1
(-9625 2875);
FORCEPROP 3 LASTPIN (-9625 2925) SIG_NAME AGND_HSC\g
J 0
(-9615 2935);
DISPLAY 0.659574 (-9615 2935);
PAINT MONO (-9615 2935);
DISPLAY INVISIBLE (-9615 2935);
FORCEPROP 1 LAST HDL_POWER AGND_HSC
J 1
(-9600 2800);
DISPLAY 0.723404 (-9600 2800);
PAINT GREEN (-9600 2800);
FORCEPROP 2 LAST CDS_LIB pure_quanta_power
J 0
(-9625 2875);
DISPLAY INVISIBLE (-9625 2875);
FORCEPROP 1 LAST PATH I66
J 0
(-9550 2875);
DISPLAY 0.872340 (-9550 2875);
PAINT AQUA (-9550 2875);
DISPLAY INVISIBLE (-9550 2875);
FORCEADD OFFPAGE..4
(-9800 3275);
FORCEPROP 2 LAST $XR1 303 
J 0
(-9494 3275);
DISPLAY 0.638298 (-9494 3275);
PAINT MONO (-9494 3275);
FORCEPROP 2 LAST $XR0 302 
J 0
(-9614 3275);
DISPLAY 0.638298 (-9614 3275);
PAINT MONO (-9614 3275);
FORCEPROP 2 LAST CDS_LIB standard
J 0
(-9800 3275);
DISPLAY INVISIBLE (-9800 3275);
FORCEPROP 1 LAST OFFPAGE TRUE
J 0
(-9475 3150);
DISPLAY 0.872340 (-9475 3150);
PAINT GREEN (-9475 3150);
DISPLAY INVISIBLE (-9475 3150);
FORCEPROP 1 LAST COMMENT_BODY TRUE
J 0
(-9825 3175);
DISPLAY 0.872340 (-9825 3175);
PAINT GREEN (-9825 3175);
DISPLAY INVISIBLE (-9825 3175);
FORCEPROP 2 LAST PATH I67
J 0
(-9475 3325);
DISPLAY 1.021277 (-9475 3325);
DISPLAY INVISIBLE (-9475 3325);
FORCEADD OFFPAGE..4
(-9800 3475);
FORCEPROP 2 LAST $XR1 303 
J 0
(-9494 3475);
DISPLAY 0.638298 (-9494 3475);
PAINT MONO (-9494 3475);
FORCEPROP 2 LAST $XR0 302 
J 0
(-9614 3475);
DISPLAY 0.638298 (-9614 3475);
PAINT MONO (-9614 3475);
FORCEPROP 2 LAST CDS_LIB standard
J 0
(-9800 3475);
DISPLAY INVISIBLE (-9800 3475);
FORCEPROP 1 LAST OFFPAGE TRUE
J 0
(-9475 3350);
DISPLAY 0.872340 (-9475 3350);
PAINT GREEN (-9475 3350);
DISPLAY INVISIBLE (-9475 3350);
FORCEPROP 1 LAST COMMENT_BODY TRUE
J 0
(-9825 3375);
DISPLAY 0.872340 (-9825 3375);
PAINT GREEN (-9825 3375);
DISPLAY INVISIBLE (-9825 3375);
FORCEPROP 2 LAST PATH I68
J 0
(-9475 3525);
DISPLAY 1.021277 (-9475 3525);
DISPLAY INVISIBLE (-9475 3525);
FORCEADD UNIVERSAL_GND..1
(-9775 3675);
FORCEPROP 3 LASTPIN (-9775 3725) SIG_NAME AGND_HSC\g
J 0
(-9765 3735);
DISPLAY 0.659574 (-9765 3735);
PAINT MONO (-9765 3735);
DISPLAY INVISIBLE (-9765 3735);
FORCEPROP 1 LAST HDL_POWER AGND_HSC
J 1
(-9750 3600);
DISPLAY 0.723404 (-9750 3600);
PAINT GREEN (-9750 3600);
FORCEPROP 2 LAST CDS_LIB pure_quanta_power
J 0
(-9775 3675);
DISPLAY INVISIBLE (-9775 3675);
FORCEPROP 1 LAST PATH I69
J 0
(-9700 3675);
DISPLAY 0.872340 (-9700 3675);
PAINT AQUA (-9700 3675);
DISPLAY INVISIBLE (-9700 3675);
FORCEADD GND..1
(-15075 900);
FORCEPROP 3 LASTPIN (-15075 950) SIG_NAME GND\g
J 0
(-15065 960);
DISPLAY 0.659574 (-15065 960);
PAINT MONO (-15065 960);
DISPLAY INVISIBLE (-15065 960);
FORCEPROP 2 LAST ROOM VR_DDR1_POWER_STAGE
J 0
(-15300 975);
FORCEPROP 1 LAST SIZE 1B
J 0
(-15000 850);
DISPLAY 0.872340 (-15000 850);
PAINT AQUA (-15000 850);
DISPLAY INVISIBLE (-15000 850);
FORCEPROP 2 LAST CDS_LIB pure_quanta_power
J 0
(-15075 900);
DISPLAY INVISIBLE (-15075 900);
FORCEPROP 1 LAST HDL_POWER GND
J 0
(-15075 1050);
DISPLAY 1.170213 (-15075 1050);
PAINT GREEN (-15075 1050);
DISPLAY INVISIBLE (-15075 1050);
FORCEPROP 1 LAST PATH I7
J 0
(-15000 900);
DISPLAY 0.872340 (-15000 900);
PAINT AQUA (-15000 900);
DISPLAY INVISIBLE (-15000 900);
FORCEADD Q_RES..2
(-10250 3975);
FORCEPROP 1 LAST LOCATION PR3932
J 0
(-10205 4100);
DISPLAY 0.978723 (-10205 4100);
FORCEPROP 0 LAST $SEC 1
J 0
(-10200 4150);
DISPLAY 0.680851 (-10200 4150);
PAINT MONO (-10200 4150);
DISPLAY INVISIBLE (-10200 4150);
FORCEPROP 0 LAST CDS_SEC 1
J 0
(-10200 4150);
DISPLAY 1.021277 (-10200 4150);
DISPLAY INVISIBLE (-10200 4150);
FORCEPROP 1 LASTPIN (-10250 4075) $PN 1
J 0
(-10245 4037);
DISPLAY 0.787234 (-10245 4037);
PAINT MONO (-10245 4037);
FORCEPROP 1 LASTPIN (-10250 3875) $PN 2
J 0
(-10245 3885);
DISPLAY 0.787234 (-10245 3885);
PAINT MONO (-10245 3885);
FORCEPROP 1 LAST PACK_TYPE 0402LF
J 0
(-10210 3800);
DISPLAY 0.638298 (-10210 3800);
FORCEPROP 1 LAST PART_NUMBER CS24992BB04
J 0
(-10210 3850);
DISPLAY 0.638298 (-10210 3850);
FORCEPROP 1 LAST MATERIAL CHIP
J 0
(-10210 3900);
DISPLAY 0.638298 (-10210 3900);
FORCEPROP 1 LAST TOLERANCE 0.1%
J 0
(-10205 4000);
DISPLAY 0.638298 (-10205 4000);
FORCEPROP 1 LAST WATTAGE 1/16W
J 0
(-10210 3950);
DISPLAY 0.638298 (-10210 3950);
FORCEPROP 1 LAST VALUE 4.99K
J 0
(-10205 4050);
DISPLAY 0.638298 (-10205 4050);
FORCEPROP 2 LAST CDS_LIB pure_quanta
J 0
(-10250 3975);
DISPLAY INVISIBLE (-10250 3975);
FORCEPROP 1 LAST PATH I70
J 0
(-10200 4150);
DISPLAY 0.978723 (-10200 4150);
PAINT WHITE (-10200 4150);
DISPLAY INVISIBLE (-10200 4150);
FORCEADD Q_RES..2
(-10325 4425);
FORCEPROP 1 LAST LOCATION PR3931
J 0
(-10280 4550);
DISPLAY 0.978723 (-10280 4550);
FORCEPROP 0 LAST $SEC 1
J 0
(-10275 4600);
DISPLAY 0.680851 (-10275 4600);
PAINT MONO (-10275 4600);
DISPLAY INVISIBLE (-10275 4600);
FORCEPROP 0 LAST CDS_SEC 1
J 0
(-10275 4600);
DISPLAY 1.021277 (-10275 4600);
DISPLAY INVISIBLE (-10275 4600);
FORCEPROP 1 LASTPIN (-10325 4525) $PN 1
J 0
(-10320 4487);
DISPLAY 0.787234 (-10320 4487);
PAINT MONO (-10320 4487);
FORCEPROP 1 LASTPIN (-10325 4325) $PN 2
J 0
(-10320 4335);
DISPLAY 0.787234 (-10320 4335);
PAINT MONO (-10320 4335);
FORCEPROP 1 LAST PART_NUMBER CS37502BB01
J 0
(-10285 4300);
DISPLAY 0.787234 (-10285 4300);
FORCEPROP 1 LAST PACK_TYPE 0402LF
J 0
(-10285 4250);
DISPLAY 0.787234 (-10285 4250);
FORCEPROP 1 LAST TOLERANCE 0.1%
J 0
(-10280 4450);
DISPLAY 0.787234 (-10280 4450);
FORCEPROP 1 LAST MATERIAL CHIP
J 0
(-10285 4350);
DISPLAY 0.787234 (-10285 4350);
FORCEPROP 1 LAST WATTAGE 1/16W
J 0
(-10285 4400);
DISPLAY 0.787234 (-10285 4400);
FORCEPROP 1 LAST VALUE 75K
J 0
(-10280 4500);
DISPLAY 0.787234 (-10280 4500);
FORCEPROP 2 LAST CDS_LIB pure_quanta
J 0
(-10325 4425);
DISPLAY INVISIBLE (-10325 4425);
FORCEPROP 1 LAST PATH I71
J 0
(-10275 4600);
DISPLAY 0.978723 (-10275 4600);
PAINT WHITE (-10275 4600);
DISPLAY INVISIBLE (-10275 4600);
FORCEADD Q_CAP..1
(-9775 3975);
FORCEPROP 1 LAST LOCATION PC2190
J 0
(-9700 4075);
DISPLAY 0.723404 (-9700 4075);
PAINT AQUA (-9700 4075);
FORCEPROP 0 LAST $SEC 1
J 0
(-9700 4125);
DISPLAY 0.680851 (-9700 4125);
PAINT MONO (-9700 4125);
DISPLAY INVISIBLE (-9700 4125);
FORCEPROP 0 LAST CDS_SEC 1
J 0
(-9700 4125);
DISPLAY 1.021277 (-9700 4125);
DISPLAY INVISIBLE (-9700 4125);
FORCEPROP 1 LASTPIN (-9775 4075) $PN 1
J 0
(-9765 4055);
DISPLAY 0.787234 (-9765 4055);
PAINT MONO (-9765 4055);
FORCEPROP 1 LASTPIN (-9775 3875) $PN 2
J 0
(-9765 3855);
DISPLAY 0.787234 (-9765 3855);
PAINT MONO (-9765 3855);
FORCEPROP 1 LAST PACK_TYPE C0402
J 0
(-9700 3825);
DISPLAY 0.723404 (-9700 3825);
PAINT SKYBLUE (-9700 3825);
FORCEPROP 1 LAST PART_NUMBER CH31006KB18
J 0
(-9700 3875);
DISPLAY 0.723404 (-9700 3875);
PAINT WHITE (-9700 3875);
FORCEPROP 1 LAST VALUE 0.01UF
J 0
(-9700 4025);
DISPLAY 0.723404 (-9700 4025);
PAINT SKYBLUE (-9700 4025);
FORCEPROP 1 LAST MATERIAL X7R
J 0
(-9700 3925);
DISPLAY 0.723404 (-9700 3925);
PAINT SKYBLUE (-9700 3925);
FORCEPROP 1 LAST VOLTAGE 50V
J 0
(-9700 3975);
DISPLAY 0.723404 (-9700 3975);
PAINT SKYBLUE (-9700 3975);
FORCEPROP 2 LAST CDS_LIB pure_quanta
J 0
(-9775 3975);
DISPLAY INVISIBLE (-9775 3975);
FORCEPROP 1 LAST TOLERANCE 10%
J 0
(-9725 3925);
DISPLAY 0.978723 (-9725 3925);
PAINT SKYBLUE (-9725 3925);
DISPLAY INVISIBLE (-9725 3925);
FORCEPROP 1 LAST PATH I72
J 0
(-9725 4125);
DISPLAY 0.978723 (-9725 4125);
PAINT WHITE (-9725 4125);
DISPLAY INVISIBLE (-9725 4125);
FORCEADD OFFPAGE..5
R 2
(-9475 1700);
FORCEPROP 2 LAST $XR2 259 
J 0
(-9046 1700);
DISPLAY 0.638298 (-9046 1700);
PAINT MONO (-9046 1700);
FORCEPROP 2 LAST $XR1 247 
J 0
(-9166 1700);
DISPLAY 0.638298 (-9166 1700);
PAINT MONO (-9166 1700);
FORCEPROP 2 LAST $XR0 214 
J 0
(-9286 1700);
DISPLAY 0.638298 (-9286 1700);
PAINT MONO (-9286 1700);
FORCEPROP 2 LAST CDS_LIB standard
J 0
(-9475 1700);
DISPLAY INVISIBLE (-9475 1700);
FORCEPROP 1 LAST OFFPAGE TRUE
J 2
(-9800 1575);
DISPLAY 0.872340 (-9800 1575);
PAINT AQUA (-9800 1575);
DISPLAY INVISIBLE (-9800 1575);
FORCEPROP 1 LAST COMMENT_BODY TRUE
J 2
(-9575 1625);
DISPLAY 1.170213 (-9575 1625);
PAINT GREEN (-9575 1625);
DISPLAY INVISIBLE (-9575 1625);
FORCEPROP 2 LAST PATH I73
J 0
(-9025 1750);
DISPLAY 1.021277 (-9025 1750);
DISPLAY INVISIBLE (-9025 1750);
FORCEADD UNIVERSAL_GND..1
(-9500 2000);
FORCEPROP 3 LASTPIN (-9500 2050) SIG_NAME AGND_HSC\g
J 0
(-9490 2060);
DISPLAY 0.659574 (-9490 2060);
PAINT MONO (-9490 2060);
DISPLAY INVISIBLE (-9490 2060);
FORCEPROP 1 LAST HDL_POWER AGND_HSC
J 1
(-9475 1925);
DISPLAY 0.723404 (-9475 1925);
PAINT GREEN (-9475 1925);
FORCEPROP 2 LAST CDS_LIB pure_quanta_power
J 0
(-9500 2000);
DISPLAY INVISIBLE (-9500 2000);
FORCEPROP 1 LAST PATH I74
J 0
(-9425 2000);
DISPLAY 0.872340 (-9425 2000);
PAINT AQUA (-9425 2000);
DISPLAY INVISIBLE (-9425 2000);
FORCEADD Q_CAP..1
(-9500 2175);
FORCEPROP 1 LAST LOCATION PC2191
J 0
(-9425 2250);
DISPLAY 0.723404 (-9425 2250);
PAINT AQUA (-9425 2250);
FORCEPROP 0 LAST $SEC 1
J 0
(-9425 2300);
DISPLAY 0.680851 (-9425 2300);
PAINT MONO (-9425 2300);
DISPLAY INVISIBLE (-9425 2300);
FORCEPROP 0 LAST CDS_SEC 1
J 0
(-9425 2300);
DISPLAY 1.021277 (-9425 2300);
DISPLAY INVISIBLE (-9425 2300);
FORCEPROP 1 LASTPIN (-9500 2275) $PN 1
J 0
(-9490 2255);
DISPLAY 0.787234 (-9490 2255);
PAINT MONO (-9490 2255);
FORCEPROP 1 LASTPIN (-9500 2075) $PN 2
J 0
(-9490 2055);
DISPLAY 0.787234 (-9490 2055);
PAINT MONO (-9490 2055);
FORCEPROP 1 LAST PART_NUMBER CH3683K1B09
J 0
(-9425 2050);
DISPLAY 0.723404 (-9425 2050);
PAINT WHITE (-9425 2050);
FORCEPROP 1 LAST VALUE 0.068UF
J 0
(-9425 2200);
DISPLAY 0.723404 (-9425 2200);
PAINT SKYBLUE (-9425 2200);
FORCEPROP 1 LAST VOLTAGE 16V
J 0
(-9425 2150);
DISPLAY 0.723404 (-9425 2150);
PAINT SKYBLUE (-9425 2150);
FORCEPROP 1 LAST PACK_TYPE 0402
J 0
(-9425 2000);
DISPLAY 0.723404 (-9425 2000);
PAINT SKYBLUE (-9425 2000);
FORCEPROP 1 LAST MATERIAL X7R
J 0
(-9425 2100);
DISPLAY 0.723404 (-9425 2100);
PAINT SKYBLUE (-9425 2100);
FORCEPROP 1 LAST TOLERANCE 10%
J 0
(-9450 2125);
DISPLAY 0.978723 (-9450 2125);
PAINT SKYBLUE (-9450 2125);
DISPLAY INVISIBLE (-9450 2125);
FORCEPROP 2 LAST CDS_LIB pure_quanta
J 0
(-9500 2175);
DISPLAY INVISIBLE (-9500 2175);
FORCEPROP 1 LAST PATH I75
J 0
(-9450 2325);
DISPLAY 0.978723 (-9450 2325);
PAINT WHITE (-9450 2325);
DISPLAY INVISIBLE (-9450 2325);
FORCEADD OFFPAGE..5
R 2
(-9375 2375);
FORCEPROP 2 LAST $XR1 303 
J 0
(-9066 2375);
DISPLAY 0.638298 (-9066 2375);
PAINT MONO (-9066 2375);
FORCEPROP 2 LAST $XR0 302 
J 0
(-9186 2375);
DISPLAY 0.638298 (-9186 2375);
PAINT MONO (-9186 2375);
FORCEPROP 2 LAST CDS_LIB standard
J 0
(-9375 2375);
DISPLAY INVISIBLE (-9375 2375);
FORCEPROP 1 LAST OFFPAGE TRUE
J 2
(-9700 2250);
DISPLAY 0.872340 (-9700 2250);
PAINT AQUA (-9700 2250);
DISPLAY INVISIBLE (-9700 2250);
FORCEPROP 1 LAST COMMENT_BODY TRUE
J 2
(-9475 2300);
DISPLAY 1.170213 (-9475 2300);
PAINT GREEN (-9475 2300);
DISPLAY INVISIBLE (-9475 2300);
FORCEPROP 2 LAST PATH I76
J 0
(-9050 2425);
DISPLAY 1.021277 (-9050 2425);
DISPLAY INVISIBLE (-9050 2425);
FORCEADD UNIVERSAL_GND..1
(-8625 2100);
FORCEPROP 3 LASTPIN (-8625 2150) SIG_NAME AGND_HSC\g
J 0
(-8615 2160);
DISPLAY 0.659574 (-8615 2160);
PAINT MONO (-8615 2160);
DISPLAY INVISIBLE (-8615 2160);
FORCEPROP 1 LAST HDL_POWER AGND_HSC
J 1
(-8600 2025);
DISPLAY 0.723404 (-8600 2025);
PAINT GREEN (-8600 2025);
FORCEPROP 2 LAST CDS_LIB pure_quanta_power
J 0
(-8625 2100);
DISPLAY INVISIBLE (-8625 2100);
FORCEPROP 1 LAST PATH I77
J 0
(-8550 2100);
DISPLAY 0.872340 (-8550 2100);
PAINT AQUA (-8550 2100);
DISPLAY INVISIBLE (-8550 2100);
FORCEADD Q_CAP..1
(-8925 2425);
FORCEPROP 1 LAST LOCATION PC2192
J 0
(-8850 2575);
DISPLAY 0.723404 (-8850 2575);
PAINT AQUA (-8850 2575);
FORCEPROP 0 LAST $SEC 1
J 0
(-8850 2625);
DISPLAY 0.680851 (-8850 2625);
PAINT MONO (-8850 2625);
DISPLAY INVISIBLE (-8850 2625);
FORCEPROP 0 LAST CDS_SEC 1
J 0
(-8850 2625);
DISPLAY 1.021277 (-8850 2625);
DISPLAY INVISIBLE (-8850 2625);
FORCEPROP 1 LASTPIN (-8925 2525) $PN 1
J 0
(-8915 2505);
DISPLAY 0.787234 (-8915 2505);
PAINT MONO (-8915 2505);
FORCEPROP 1 LASTPIN (-8925 2325) $PN 2
J 0
(-8915 2305);
DISPLAY 0.787234 (-8915 2305);
PAINT MONO (-8915 2305);
FORCEPROP 1 LAST PACK_TYPE C0402
J 0
(-8850 2325);
DISPLAY 0.723404 (-8850 2325);
PAINT SKYBLUE (-8850 2325);
FORCEPROP 1 LAST MATERIAL X7R
J 0
(-8850 2425);
DISPLAY 0.723404 (-8850 2425);
PAINT SKYBLUE (-8850 2425);
FORCEPROP 1 LAST VALUE 0.001UF
J 0
(-8850 2525);
DISPLAY 0.723404 (-8850 2525);
PAINT SKYBLUE (-8850 2525);
FORCEPROP 1 LAST VOLTAGE 50V
J 0
(-8850 2475);
DISPLAY 0.723404 (-8850 2475);
PAINT SKYBLUE (-8850 2475);
FORCEPROP 1 LAST PART_NUMBER CH30106KB19
J 0
(-8850 2375);
DISPLAY 0.723404 (-8850 2375);
PAINT WHITE (-8850 2375);
FORCEPROP 1 LAST TOLERANCE 10%
J 0
(-8875 2375);
DISPLAY 0.978723 (-8875 2375);
PAINT SKYBLUE (-8875 2375);
DISPLAY INVISIBLE (-8875 2375);
FORCEPROP 2 LAST CDS_LIB pure_quanta
J 0
(-8925 2425);
DISPLAY INVISIBLE (-8925 2425);
FORCEPROP 1 LAST PATH I78
J 0
(-8875 2575);
DISPLAY 0.978723 (-8875 2575);
PAINT WHITE (-8875 2575);
DISPLAY INVISIBLE (-8875 2575);
FORCEADD Q_RES..1
(-8950 3575);
FORCEPROP 1 LAST LOCATION R2588
J 0
(-9225 3600);
DISPLAY 0.723404 (-9225 3600);
PAINT AQUA (-9225 3600);
FORCEPROP 0 LAST $SEC 1
J 0
(-8900 3650);
DISPLAY 0.680851 (-8900 3650);
PAINT MONO (-8900 3650);
DISPLAY INVISIBLE (-8900 3650);
FORCEPROP 0 LAST CDS_SEC 1
J 0
(-8900 3650);
DISPLAY 1.021277 (-8900 3650);
DISPLAY INVISIBLE (-8900 3650);
FORCEPROP 1 LASTPIN (-9050 3575) $PN 1
J 0
(-9038 3587);
DISPLAY 0.787234 (-9038 3587);
PAINT MONO (-9038 3587);
FORCEPROP 1 LASTPIN (-8850 3575) $PN 2
J 0
(-8888 3587);
DISPLAY 0.787234 (-8888 3587);
PAINT MONO (-8888 3587);
FORCEPROP 1 LAST PACK_TYPE 0402LF
J 0
(-8775 3475);
DISPLAY 0.723404 (-8775 3475);
PAINT SKYBLUE (-8775 3475);
FORCEPROP 1 LAST PART_NUMBER CS02202FB02
J 0
(-8825 3600);
DISPLAY 0.723404 (-8825 3600);
PAINT WHITE (-8825 3600);
FORCEPROP 1 LAST TOLERANCE 1%
J 0
(-8850 3525);
DISPLAY 0.723404 (-8850 3525);
PAINT SKYBLUE (-8850 3525);
FORCEPROP 1 LAST MATERIAL CHIP
J 0
(-8975 3475);
DISPLAY 0.723404 (-8975 3475);
PAINT SKYBLUE (-8975 3475);
FORCEPROP 1 LAST WATTAGE 1/16W
J 2
(-9000 3475);
DISPLAY 0.723404 (-9000 3475);
PAINT SKYBLUE (-9000 3475);
FORCEPROP 1 LAST VALUE 22
J 2
(-9025 3525);
DISPLAY 0.723404 (-9025 3525);
PAINT SKYBLUE (-9025 3525);
FORCEPROP 2 LAST CDS_LIB pure_quanta
J 0
(-8950 3575);
DISPLAY INVISIBLE (-8950 3575);
FORCEPROP 1 LAST PATH I79
J 0
(-9000 3725);
DISPLAY 0.978723 (-9000 3725);
PAINT WHITE (-9000 3725);
DISPLAY INVISIBLE (-9000 3725);
FORCEADD CONN3_210HP1030BR1..1
(-14825 1100);
PAINT AQUA (-14825 1100);
FORCEPROP 1 LAST LOCATION JP4003
J 0
(-14875 1325);
DISPLAY 0.723404 (-14875 1325);
PAINT AQUA (-14875 1325);
FORCEPROP 0 LAST $SEC 1
J 0
(-14875 1475);
DISPLAY 0.680851 (-14875 1475);
PAINT MONO (-14875 1475);
DISPLAY INVISIBLE (-14875 1475);
FORCEPROP 0 LAST CDS_SEC 1
J 0
(-14875 1475);
DISPLAY 1.021277 (-14875 1475);
DISPLAY INVISIBLE (-14875 1475);
FORCEPROP 0 LASTPIN (-15025 1150) $PN 1
J 2
(-15035 1160);
DISPLAY 0.680851 (-15035 1160);
PAINT MONO (-15035 1160);
FORCEPROP 0 LASTPIN (-15025 1100) $PN 2
J 2
(-15035 1110);
DISPLAY 0.680851 (-15035 1110);
PAINT MONO (-15035 1110);
FORCEPROP 0 LASTPIN (-15025 1050) $PN 3
J 2
(-15035 1060);
DISPLAY 0.680851 (-15035 1060);
PAINT MONO (-15035 1060);
FORCEPROP 2 LAST VALUE CONN3_210-HP1-030BR1
J 0
(-14875 1375);
DISPLAY 0.723404 (-14875 1375);
PAINT AQUA (-14875 1375);
FORCEPROP 2 LAST PART_TYPE THLF
J 0
(-14875 1425);
DISPLAY 1.021277 (-14875 1425);
FORCEPROP 1 LAST PART_NUMBER DFHD03MS213
J 0
(-14875 1275);
DISPLAY 0.723404 (-14875 1275);
PAINT WHITE (-14875 1275);
FORCEPROP 1 LAST MATERIAL IO
J 0
(-14888 1224);
DISPLAY 0.723404 (-14888 1224);
PAINT SKYBLUE (-14888 1224);
FORCEPROP 1 LAST NEEDS_NO_SIZE TRUE
J 0
(-14825 1100);
DISPLAY 0.723404 (-14825 1100);
PAINT GREEN (-14825 1100);
DISPLAY INVISIBLE (-14825 1100);
FORCEPROP 1 LAST CDS_LMAN_SYM_OUTLINE -50,100,50,-100
J 0
(-14825 1100);
DISPLAY 0.468085 (-14825 1100);
PAINT GREEN (-14825 1100);
DISPLAY INVISIBLE (-14825 1100);
FORCEPROP 2 LAST CDS_LIB pure_quanta
J 0
(-14825 1100);
DISPLAY INVISIBLE (-14825 1100);
FORCEPROP 1 LAST PATH I8
J 0
(-14825 1100);
DISPLAY 0.723404 (-14825 1100);
PAINT GREEN (-14825 1100);
DISPLAY INVISIBLE (-14825 1100);
FORCEADD Q_RES..1
(-8950 3400);
FORCEPROP 1 LAST LOCATION R3934
J 0
(-9225 3425);
DISPLAY 0.723404 (-9225 3425);
PAINT AQUA (-9225 3425);
FORCEPROP 0 LAST $SEC 1
J 0
(-8900 3475);
DISPLAY 0.680851 (-8900 3475);
PAINT MONO (-8900 3475);
DISPLAY INVISIBLE (-8900 3475);
FORCEPROP 0 LAST CDS_SEC 1
J 0
(-8900 3475);
DISPLAY 1.021277 (-8900 3475);
DISPLAY INVISIBLE (-8900 3475);
FORCEPROP 1 LASTPIN (-9050 3400) $PN 1
J 0
(-9038 3412);
DISPLAY 0.787234 (-9038 3412);
PAINT MONO (-9038 3412);
FORCEPROP 1 LASTPIN (-8850 3400) $PN 2
J 0
(-8888 3412);
DISPLAY 0.787234 (-8888 3412);
PAINT MONO (-8888 3412);
FORCEPROP 1 LAST PART_NUMBER CS02202FB02
J 0
(-8825 3425);
DISPLAY 0.723404 (-8825 3425);
PAINT WHITE (-8825 3425);
FORCEPROP 1 LAST VALUE 22
J 2
(-9025 3350);
DISPLAY 0.723404 (-9025 3350);
PAINT SKYBLUE (-9025 3350);
FORCEPROP 1 LAST TOLERANCE 1%
J 0
(-8850 3350);
DISPLAY 0.723404 (-8850 3350);
PAINT SKYBLUE (-8850 3350);
FORCEPROP 1 LAST MATERIAL CHIP
J 0
(-8975 3300);
DISPLAY 0.723404 (-8975 3300);
PAINT SKYBLUE (-8975 3300);
FORCEPROP 1 LAST PACK_TYPE 0402LF
J 0
(-8775 3300);
DISPLAY 0.723404 (-8775 3300);
PAINT SKYBLUE (-8775 3300);
FORCEPROP 1 LAST WATTAGE 1/16W
J 2
(-9000 3300);
DISPLAY 0.723404 (-9000 3300);
PAINT SKYBLUE (-9000 3300);
FORCEPROP 2 LAST CDS_LIB pure_quanta
J 0
(-8950 3400);
DISPLAY INVISIBLE (-8950 3400);
FORCEPROP 1 LAST PATH I80
J 0
(-9000 3550);
DISPLAY 0.978723 (-9000 3550);
PAINT WHITE (-9000 3550);
DISPLAY INVISIBLE (-9000 3550);
FORCEADD Q_RES..2
(-8450 2450);
FORCEPROP 1 LAST LOCATION PR3935
J 0
(-8395 2600);
DISPLAY 0.723404 (-8395 2600);
PAINT AQUA (-8395 2600);
FORCEPROP 0 LAST $SEC 1
J 0
(-8375 2650);
DISPLAY 0.680851 (-8375 2650);
PAINT MONO (-8375 2650);
DISPLAY INVISIBLE (-8375 2650);
FORCEPROP 0 LAST CDS_SEC 1
J 0
(-8375 2650);
DISPLAY 1.021277 (-8375 2650);
DISPLAY INVISIBLE (-8375 2650);
FORCEPROP 1 LASTPIN (-8450 2550) $PN 1
J 0
(-8445 2512);
DISPLAY 0.787234 (-8445 2512);
PAINT MONO (-8445 2512);
FORCEPROP 1 LASTPIN (-8450 2350) $PN 2
J 0
(-8445 2360);
DISPLAY 0.787234 (-8445 2360);
PAINT MONO (-8445 2360);
FORCEPROP 1 LAST VALUE 10K
J 0
(-8395 2550);
DISPLAY 0.723404 (-8395 2550);
PAINT SKYBLUE (-8395 2550);
FORCEPROP 1 LAST TOLERANCE 1%
J 0
(-8395 2500);
DISPLAY 0.723404 (-8395 2500);
PAINT SKYBLUE (-8395 2500);
FORCEPROP 1 LAST PART_NUMBER CS31002FB08
J 0
(-8400 2350);
DISPLAY 0.723404 (-8400 2350);
PAINT WHITE (-8400 2350);
FORCEPROP 1 LAST WATTAGE 1/16W
J 0
(-8400 2450);
DISPLAY 0.723404 (-8400 2450);
PAINT SKYBLUE (-8400 2450);
FORCEPROP 1 LAST PACK_TYPE 0402LF
J 0
(-8400 2300);
DISPLAY 0.723404 (-8400 2300);
PAINT SKYBLUE (-8400 2300);
FORCEPROP 1 LAST MATERIAL CHIP
J 0
(-8400 2400);
DISPLAY 0.723404 (-8400 2400);
PAINT SKYBLUE (-8400 2400);
FORCEPROP 2 LAST CDS_LIB pure_quanta
J 0
(-8450 2450);
DISPLAY INVISIBLE (-8450 2450);
FORCEPROP 1 LAST PATH I81
J 0
(-8400 2625);
DISPLAY 0.978723 (-8400 2625);
PAINT WHITE (-8400 2625);
DISPLAY INVISIBLE (-8400 2625);
FORCEADD OFFPAGE..4
(-8300 2675);
FORCEPROP 2 LAST $XR1 303 
J 0
(-7994 2675);
DISPLAY 0.638298 (-7994 2675);
PAINT MONO (-7994 2675);
FORCEPROP 2 LAST $XR0 302 
J 0
(-8114 2675);
DISPLAY 0.638298 (-8114 2675);
PAINT MONO (-8114 2675);
FORCEPROP 2 LAST CDS_LIB standard
J 2
(-8300 2675);
DISPLAY INVISIBLE (-8300 2675);
FORCEPROP 1 LAST OFFPAGE TRUE
J 0
(-7975 2550);
DISPLAY 0.872340 (-7975 2550);
PAINT GREEN (-7975 2550);
DISPLAY INVISIBLE (-7975 2550);
FORCEPROP 1 LAST COMMENT_BODY TRUE
J 0
(-8325 2575);
DISPLAY 0.872340 (-8325 2575);
PAINT GREEN (-8325 2575);
DISPLAY INVISIBLE (-8325 2575);
FORCEPROP 2 LAST PATH I82
J 0
(-7975 2725);
DISPLAY 1.021277 (-7975 2725);
DISPLAY INVISIBLE (-7975 2725);
FORCEADD UNIVERSAL_GND..1
(-7625 2600);
FORCEPROP 3 LASTPIN (-7625 2650) SIG_NAME AGND_HSC\g
J 0
(-7615 2660);
DISPLAY 0.659574 (-7615 2660);
PAINT MONO (-7615 2660);
DISPLAY INVISIBLE (-7615 2660);
FORCEPROP 1 LAST HDL_POWER AGND_HSC
J 1
(-7600 2525);
DISPLAY 0.723404 (-7600 2525);
PAINT GREEN (-7600 2525);
FORCEPROP 2 LAST CDS_LIB pure_quanta_power
J 0
(-7625 2600);
DISPLAY INVISIBLE (-7625 2600);
FORCEPROP 1 LAST PATH I83
J 0
(-7550 2600);
DISPLAY 0.872340 (-7550 2600);
PAINT AQUA (-7550 2600);
DISPLAY INVISIBLE (-7550 2600);
FORCEADD Q_CAP..1
(-8100 2850);
FORCEPROP 1 LAST LOCATION PC2193
J 0
(-8025 3000);
DISPLAY 0.723404 (-8025 3000);
PAINT AQUA (-8025 3000);
FORCEPROP 0 LAST $SEC 1
J 0
(-8025 3050);
DISPLAY 0.680851 (-8025 3050);
PAINT MONO (-8025 3050);
DISPLAY INVISIBLE (-8025 3050);
FORCEPROP 0 LAST CDS_SEC 1
J 0
(-8025 3050);
DISPLAY 1.021277 (-8025 3050);
DISPLAY INVISIBLE (-8025 3050);
FORCEPROP 1 LASTPIN (-8100 2950) $PN 1
J 0
(-8090 2930);
DISPLAY 0.787234 (-8090 2930);
PAINT MONO (-8090 2930);
FORCEPROP 1 LASTPIN (-8100 2750) $PN 2
J 0
(-8090 2730);
DISPLAY 0.787234 (-8090 2730);
PAINT MONO (-8090 2730);
FORCEPROP 1 LAST PACK_TYPE C0402
J 0
(-8025 2750);
DISPLAY 0.723404 (-8025 2750);
PAINT SKYBLUE (-8025 2750);
FORCEPROP 1 LAST VALUE 0.047UF
J 0
(-8025 2950);
DISPLAY 0.723404 (-8025 2950);
PAINT SKYBLUE (-8025 2950);
FORCEPROP 1 LAST MATERIAL X7R
J 0
(-8025 2850);
DISPLAY 0.723404 (-8025 2850);
PAINT SKYBLUE (-8025 2850);
FORCEPROP 1 LAST VOLTAGE 25V
J 0
(-8025 2900);
DISPLAY 0.723404 (-8025 2900);
PAINT SKYBLUE (-8025 2900);
FORCEPROP 1 LAST PART_NUMBER CH3474K1B04
J 0
(-8025 2800);
DISPLAY 0.723404 (-8025 2800);
PAINT WHITE (-8025 2800);
FORCEPROP 2 LAST CDS_LIB pure_quanta
J 0
(-8100 2850);
DISPLAY INVISIBLE (-8100 2850);
FORCEPROP 1 LAST TOLERANCE 10%
J 0
(-8050 2800);
DISPLAY 0.978723 (-8050 2800);
PAINT SKYBLUE (-8050 2800);
DISPLAY INVISIBLE (-8050 2800);
FORCEPROP 1 LAST PATH I84
J 0
(-8050 3000);
DISPLAY 0.978723 (-8050 3000);
PAINT WHITE (-8050 3000);
DISPLAY INVISIBLE (-8050 3000);
FORCEADD Q_RES..1
(-8125 3275);
FORCEPROP 1 LAST LOCATION PR3937
J 0
(-8425 3300);
DISPLAY 0.723404 (-8425 3300);
PAINT AQUA (-8425 3300);
FORCEPROP 0 LAST $SEC 1
J 0
(-8075 3350);
DISPLAY 0.680851 (-8075 3350);
PAINT MONO (-8075 3350);
DISPLAY INVISIBLE (-8075 3350);
FORCEPROP 0 LAST CDS_SEC 1
J 0
(-8075 3350);
DISPLAY 1.021277 (-8075 3350);
DISPLAY INVISIBLE (-8075 3350);
FORCEPROP 1 LASTPIN (-8225 3275) $PN 1
J 0
(-8213 3287);
DISPLAY 0.787234 (-8213 3287);
PAINT MONO (-8213 3287);
FORCEPROP 1 LASTPIN (-8025 3275) $PN 2
J 0
(-8063 3287);
DISPLAY 0.787234 (-8063 3287);
PAINT MONO (-8063 3287);
FORCEPROP 1 LAST PACK_TYPE 0402LF
J 0
(-7975 3175);
DISPLAY 0.723404 (-7975 3175);
PAINT SKYBLUE (-7975 3175);
FORCEPROP 1 LAST MATERIAL CHIP
J 0
(-8175 3175);
DISPLAY 0.723404 (-8175 3175);
PAINT SKYBLUE (-8175 3175);
FORCEPROP 1 LAST VALUE 120K
J 2
(-8175 3225);
DISPLAY 0.723404 (-8175 3225);
PAINT SKYBLUE (-8175 3225);
FORCEPROP 1 LAST WATTAGE 1/16W
J 2
(-8225 3175);
DISPLAY 0.723404 (-8225 3175);
PAINT SKYBLUE (-8225 3175);
FORCEPROP 1 LAST PART_NUMBER CS41202FB05
J 0
(-7975 3300);
DISPLAY 0.723404 (-7975 3300);
PAINT WHITE (-7975 3300);
FORCEPROP 1 LAST TOLERANCE 1%
J 0
(-8025 3225);
DISPLAY 0.723404 (-8025 3225);
PAINT SKYBLUE (-8025 3225);
FORCEPROP 2 LAST CDS_LIB pure_quanta
J 0
(-8125 3275);
DISPLAY INVISIBLE (-8125 3275);
FORCEPROP 1 LAST PATH I85
J 0
(-8175 3425);
DISPLAY 0.978723 (-8175 3425);
PAINT WHITE (-8175 3425);
DISPLAY INVISIBLE (-8175 3425);
FORCEADD Q_RES..2
(-7625 2875);
FORCEPROP 1 LAST $LOCATION PR1133
J 0
(-7570 3025);
DISPLAY 0.723404 (-7570 3025);
PAINT AQUA (-7570 3025);
FORCEPROP 0 LAST CDS_LOCATION PR1133
J 0
(-7550 3075);
DISPLAY 1.021277 (-7550 3075);
DISPLAY INVISIBLE (-7550 3075);
FORCEPROP 0 LAST $SEC 1
J 0
(-7550 3075);
DISPLAY 0.680851 (-7550 3075);
PAINT MONO (-7550 3075);
DISPLAY INVISIBLE (-7550 3075);
FORCEPROP 0 LAST CDS_SEC 1
J 0
(-7550 3075);
DISPLAY 1.021277 (-7550 3075);
DISPLAY INVISIBLE (-7550 3075);
FORCEPROP 1 LASTPIN (-7625 2975) $PN 1
J 0
(-7620 2937);
DISPLAY 0.787234 (-7620 2937);
PAINT MONO (-7620 2937);
FORCEPROP 1 LASTPIN (-7625 2775) $PN 2
J 0
(-7620 2785);
DISPLAY 0.787234 (-7620 2785);
PAINT MONO (-7620 2785);
FORCEPROP 1 LAST PACK_TYPE 0402LF
J 0
(-7575 2725);
DISPLAY 0.723404 (-7575 2725);
PAINT SKYBLUE (-7575 2725);
FORCEPROP 1 LAST PART_NUMBER CS22002BB07
J 0
(-7575 2775);
DISPLAY 0.723404 (-7575 2775);
PAINT WHITE (-7575 2775);
FORCEPROP 1 LAST VALUE 2K
J 0
(-7570 2975);
DISPLAY 0.723404 (-7570 2975);
PAINT SKYBLUE (-7570 2975);
FORCEPROP 1 LAST TOLERANCE 0.1%
J 0
(-7570 2925);
DISPLAY 0.723404 (-7570 2925);
PAINT SKYBLUE (-7570 2925);
FORCEPROP 1 LAST MATERIAL CHIP
J 0
(-7575 2825);
DISPLAY 0.723404 (-7575 2825);
PAINT SKYBLUE (-7575 2825);
FORCEPROP 1 LAST WATTAGE 1/16W
J 0
(-7575 2875);
DISPLAY 0.723404 (-7575 2875);
PAINT SKYBLUE (-7575 2875);
FORCEPROP 2 LAST CDS_LIB pure_quanta
J 0
(-7625 2875);
DISPLAY INVISIBLE (-7625 2875);
FORCEPROP 1 LAST PATH I86
J 0
(-7575 3050);
DISPLAY 0.978723 (-7575 3050);
PAINT WHITE (-7575 3050);
DISPLAY INVISIBLE (-7575 3050);
FORCEADD UNIVERSAL_GND..1
(-7550 3200);
FORCEPROP 3 LASTPIN (-7550 3250) SIG_NAME AGND_HSC\g
J 0
(-7540 3260);
DISPLAY 0.659574 (-7540 3260);
PAINT MONO (-7540 3260);
DISPLAY INVISIBLE (-7540 3260);
FORCEPROP 1 LAST HDL_POWER AGND_HSC
J 1
(-7525 3150);
DISPLAY 0.723404 (-7525 3150);
PAINT GREEN (-7525 3150);
FORCEPROP 2 LAST CDS_LIB pure_quanta_power
J 0
(-7550 3200);
DISPLAY INVISIBLE (-7550 3200);
FORCEPROP 1 LAST PATH I87
J 0
(-7475 3200);
DISPLAY 0.872340 (-7475 3200);
PAINT AQUA (-7475 3200);
DISPLAY INVISIBLE (-7475 3200);
FORCEADD GND..1
(-9175 3725);
FORCEPROP 3 LASTPIN (-9175 3775) SIG_NAME GND\g
J 0
(-9165 3785);
DISPLAY 0.659574 (-9165 3785);
PAINT MONO (-9165 3785);
DISPLAY INVISIBLE (-9165 3785);
FORCEPROP 2 LAST ROOM VR_DDR1_POWER_STAGE
J 0
(-9400 3800);
FORCEPROP 2 LAST CDS_LIB pure_quanta_power
J 0
(-9175 3725);
DISPLAY INVISIBLE (-9175 3725);
FORCEPROP 1 LAST SIZE 1B
J 0
(-9100 3675);
DISPLAY 0.872340 (-9100 3675);
PAINT AQUA (-9100 3675);
DISPLAY INVISIBLE (-9100 3675);
FORCEPROP 1 LAST HDL_POWER GND
J 0
(-9175 3875);
DISPLAY 1.170213 (-9175 3875);
PAINT GREEN (-9175 3875);
DISPLAY INVISIBLE (-9175 3875);
FORCEPROP 1 LAST PATH I88
J 0
(-9100 3725);
DISPLAY 0.872340 (-9100 3725);
PAINT AQUA (-9100 3725);
DISPLAY INVISIBLE (-9100 3725);
FORCEADD SS15P3SM386A..1
R 1
(-9175 4225);
FORCEPROP 1 LAST LOCATION PD111
J 0
(-9075 4275);
DISPLAY 0.723404 (-9075 4275);
PAINT AQUA (-9075 4275);
FORCEPROP 0 LAST $SEC 1
R 1
J 0
(-9075 4325);
DISPLAY 0.680851 (-9075 4325);
PAINT MONO (-9075 4325);
DISPLAY INVISIBLE (-9075 4325);
FORCEPROP 0 LAST CDS_SEC 1
R 1
J 0
(-9075 4325);
DISPLAY 1.021277 (-9075 4325);
DISPLAY INVISIBLE (-9075 4325);
FORCEPROP 0 LASTPIN (-9225 3950) $PN 1
R 1
J 2
(-9235 3940);
DISPLAY 0.680851 (-9235 3940);
PAINT MONO (-9235 3940);
FORCEPROP 0 LASTPIN (-9125 3950) $PN 2
R 1
J 2
(-9135 3940);
DISPLAY 0.680851 (-9135 3940);
PAINT MONO (-9135 3940);
FORCEPROP 0 LASTPIN (-9175 4500) $PN K
R 1
J 0
(-9185 4510);
DISPLAY 0.680851 (-9185 4510);
PAINT MONO (-9185 4510);
FORCEPROP 2 LAST VALUE SS15P3S-M3/86A
J 0
(-9075 4125);
DISPLAY 0.808511 (-9075 4125);
PAINT SKYBLUE (-9075 4125);
FORCEPROP 1 LAST PART_NUMBER BC015P3SZ00
J 0
(-9075 4075);
DISPLAY 0.723404 (-9075 4075);
PAINT WHITE (-9075 4075);
FORCEPROP 1 LAST MATERIAL IC
J 0
(-9075 4025);
DISPLAY 0.723404 (-9075 4025);
PAINT SKYBLUE (-9075 4025);
FORCEPROP 2 LAST PART_TYPE SMLF
J 0
(-9075 4200);
DISPLAY 1.021277 (-9075 4200);
FORCEPROP 1 LAST CDS_LMAN_SYM_OUTLINE -125,100,125,-100
R 1
J 0
(-9175 4225);
DISPLAY 0.468085 (-9175 4225);
PAINT GREEN (-9175 4225);
DISPLAY INVISIBLE (-9175 4225);
FORCEPROP 1 LAST NEEDS_NO_SIZE TRUE
R 1
J 0
(-9175 4225);
DISPLAY 0.723404 (-9175 4225);
PAINT GREEN (-9175 4225);
DISPLAY INVISIBLE (-9175 4225);
FORCEPROP 2 LAST CDS_LIB pure_quanta
R 1
J 0
(-9175 4225);
DISPLAY INVISIBLE (-9175 4225);
FORCEPROP 1 LAST PATH I89
R 1
J 0
(-9175 4225);
DISPLAY 0.723404 (-9175 4225);
PAINT GREEN (-9175 4225);
DISPLAY INVISIBLE (-9175 4225);
FORCEADD MOSFET_NCH_GDS_ESD_PROTECTED..1
(-14300 -75);
FORCEPROP 1 LAST $LOCATION U290
J 0
(-14158 -111);
DISPLAY 0.574468 (-14158 -111);
PAINT GREEN (-14158 -111);
FORCEPROP 0 LAST CDS_LOCATION U290
J 0
(-14150 25);
DISPLAY 1.021277 (-14150 25);
DISPLAY INVISIBLE (-14150 25);
FORCEPROP 0 LAST $SEC 1
J 0
(-14150 25);
DISPLAY 0.680851 (-14150 25);
PAINT MONO (-14150 25);
DISPLAY INVISIBLE (-14150 25);
FORCEPROP 0 LAST CDS_SEC 1
J 0
(-14150 25);
DISPLAY 1.021277 (-14150 25);
DISPLAY INVISIBLE (-14150 25);
FORCEPROP 0 LASTPIN (-14275 125) $PN D
R 1
J 0
(-14285 135);
DISPLAY 0.680851 (-14285 135);
PAINT MONO (-14285 135);
FORCEPROP 0 LASTPIN (-14475 -75) $PN G
J 2
(-14485 -65);
DISPLAY 0.680851 (-14485 -65);
PAINT MONO (-14485 -65);
FORCEPROP 0 LASTPIN (-14275 -275) $PN S
R 1
J 2
(-14285 -285);
DISPLAY 0.680851 (-14285 -285);
PAINT MONO (-14285 -285);
FORCEPROP 2 LAST VALUE 2N7002K
J 0
(-14150 -75);
DISPLAY 0.808511 (-14150 -75);
FORCEPROP 1 LAST PART_NUMBER BAM70020002
J 0
(-14158 -163);
DISPLAY 0.574468 (-14158 -163);
PAINT GREEN (-14158 -163);
FORCEPROP 1 LAST MATERIAL IC
J 0
(-14158 -220);
DISPLAY 0.574468 (-14158 -220);
PAINT GREEN (-14158 -220);
FORCEPROP 2 LAST PART_TYPE SMLF
J 0
(-14150 -25);
DISPLAY 0.808511 (-14150 -25);
FORCEPROP 1 LAST NEEDS_NO_SIZE TRUE
J 0
(-14175 -185);
DISPLAY 0.723404 (-14175 -185);
PAINT GREEN (-14175 -185);
DISPLAY INVISIBLE (-14175 -185);
FORCEPROP 2 LAST CDS_LIB pure_quanta
J 0
(-14300 -75);
DISPLAY INVISIBLE (-14300 -75);
FORCEPROP 1 LAST CDS_LMAN_SYM_OUTLINE -125,150,125,-150
J 0
(-14300 -75);
DISPLAY 0.468085 (-14300 -75);
PAINT GREEN (-14300 -75);
DISPLAY INVISIBLE (-14300 -75);
FORCEPROP 1 LAST PATH I9
J 0
(-14175 -225);
DISPLAY 0.723404 (-14175 -225);
PAINT GREEN (-14175 -225);
DISPLAY INVISIBLE (-14175 -225);
FORCEADD UNIVERSAL_POWER..1
(-8575 4800);
FORCEPROP 3 LASTPIN (-8575 4750) SIG_NAME P12V_AUX\g
J 0
(-8565 4760);
DISPLAY 0.659574 (-8565 4760);
PAINT MONO (-8565 4760);
DISPLAY INVISIBLE (-8565 4760);
FORCEPROP 1 LAST HDL_POWER P12V_AUX
J 1
(-8575 4850);
DISPLAY 0.723404 (-8575 4850);
PAINT GREEN (-8575 4850);
FORCEPROP 2 LAST ROOM AUX_SW
J 0
(-8575 4900);
DISPLAY 0.617021 (-8575 4900);
FORCEPROP 2 LAST CDS_LIB pure_quanta_power
J 0
(-8575 4800);
DISPLAY INVISIBLE (-8575 4800);
FORCEPROP 2 LAST BOM_COST MIO_VRD_SB
J 0
(-8575 4900);
DISPLAY 0.617021 (-8575 4900);
PAINT PURPLE (-8575 4900);
DISPLAY INVISIBLE (-8575 4900);
FORCEPROP 1 LAST PATH I90
J 0
(-8525 4825);
DISPLAY 0.872340 (-8525 4825);
PAINT AQUA (-8525 4825);
DISPLAY INVISIBLE (-8525 4825);
FORCEADD Q_RES..2
(-8425 3900);
FORCEPROP 1 LAST LOCATION R3936
J 0
(-8380 4025);
DISPLAY 0.723404 (-8380 4025);
PAINT AQUA (-8380 4025);
FORCEPROP 0 LAST $SEC 1
J 0
(-8375 4075);
DISPLAY 0.680851 (-8375 4075);
PAINT MONO (-8375 4075);
DISPLAY INVISIBLE (-8375 4075);
FORCEPROP 0 LAST CDS_SEC 1
J 0
(-8375 4075);
DISPLAY 1.021277 (-8375 4075);
DISPLAY INVISIBLE (-8375 4075);
FORCEPROP 1 LASTPIN (-8425 4000) $PN 1
J 0
(-8420 3962);
DISPLAY 0.787234 (-8420 3962);
PAINT MONO (-8420 3962);
FORCEPROP 1 LASTPIN (-8425 3800) $PN 2
J 0
(-8420 3810);
DISPLAY 0.787234 (-8420 3810);
PAINT MONO (-8420 3810);
FORCEPROP 1 LAST PART_NUMBER CS24702FB06
J 0
(-8385 3775);
DISPLAY 0.723404 (-8385 3775);
PAINT WHITE (-8385 3775);
FORCEPROP 1 LAST MATERIAL CHIP
J 0
(-8385 3825);
DISPLAY 0.723404 (-8385 3825);
PAINT SKYBLUE (-8385 3825);
FORCEPROP 1 LAST WATTAGE 1/16W
J 0
(-8385 3875);
DISPLAY 0.723404 (-8385 3875);
PAINT SKYBLUE (-8385 3875);
FORCEPROP 1 LAST TOLERANCE 1%
J 0
(-8380 3925);
DISPLAY 0.723404 (-8380 3925);
PAINT SKYBLUE (-8380 3925);
FORCEPROP 1 LAST PACK_TYPE 0402LF
J 0
(-8385 3725);
DISPLAY 0.723404 (-8385 3725);
PAINT SKYBLUE (-8385 3725);
FORCEPROP 1 LAST VALUE 4.7K
J 0
(-8380 3975);
DISPLAY 0.723404 (-8380 3975);
PAINT SKYBLUE (-8380 3975);
FORCEPROP 2 LAST CDS_LIB pure_quanta
J 0
(-8425 3900);
DISPLAY INVISIBLE (-8425 3900);
FORCEPROP 1 LAST PATH I91
J 0
(-8375 4075);
DISPLAY 0.978723 (-8375 4075);
PAINT WHITE (-8375 4075);
DISPLAY INVISIBLE (-8375 4075);
FORCEADD UNIVERSAL_POWER..1
(-8225 4250);
FORCEPROP 3 LASTPIN (-8225 4200) SIG_NAME HSC_VDD\g
J 0
(-8215 4210);
DISPLAY 0.659574 (-8215 4210);
PAINT MONO (-8215 4210);
DISPLAY INVISIBLE (-8215 4210);
FORCEPROP 1 LAST HDL_POWER HSC_VDD
J 1
(-8225 4300);
DISPLAY 0.723404 (-8225 4300);
PAINT GREEN (-8225 4300);
FORCEPROP 2 LAST ROOM AUX_SW
J 0
(-8225 4350);
DISPLAY 0.617021 (-8225 4350);
FORCEPROP 2 LAST BOM_COST MIO_VRD_SB
J 0
(-8225 4350);
DISPLAY 0.617021 (-8225 4350);
PAINT PURPLE (-8225 4350);
DISPLAY INVISIBLE (-8225 4350);
FORCEPROP 2 LAST CDS_LIB pure_quanta_power
J 0
(-8225 4250);
DISPLAY INVISIBLE (-8225 4250);
FORCEPROP 1 LAST PATH I92
J 0
(-8175 4275);
DISPLAY 0.872340 (-8175 4275);
PAINT AQUA (-8175 4275);
DISPLAY INVISIBLE (-8175 4275);
FORCEADD Q_RES..2
(-8000 3900);
FORCEPROP 1 LAST LOCATION R2587
J 0
(-7955 4025);
DISPLAY 0.723404 (-7955 4025);
PAINT AQUA (-7955 4025);
FORCEPROP 0 LAST $SEC 1
J 0
(-7950 4075);
DISPLAY 0.680851 (-7950 4075);
PAINT MONO (-7950 4075);
DISPLAY INVISIBLE (-7950 4075);
FORCEPROP 0 LAST CDS_SEC 1
J 0
(-7950 4075);
DISPLAY 1.021277 (-7950 4075);
DISPLAY INVISIBLE (-7950 4075);
FORCEPROP 1 LASTPIN (-8000 4000) $PN 1
J 0
(-7995 3962);
DISPLAY 0.787234 (-7995 3962);
PAINT MONO (-7995 3962);
FORCEPROP 1 LASTPIN (-8000 3800) $PN 2
J 0
(-7995 3810);
DISPLAY 0.787234 (-7995 3810);
PAINT MONO (-7995 3810);
FORCEPROP 1 LAST PACK_TYPE 0402LF
J 0
(-7960 3725);
DISPLAY 0.723404 (-7960 3725);
PAINT SKYBLUE (-7960 3725);
FORCEPROP 1 LAST WATTAGE 1/16W
J 0
(-7960 3875);
DISPLAY 0.723404 (-7960 3875);
PAINT SKYBLUE (-7960 3875);
FORCEPROP 1 LAST MATERIAL CHIP
J 0
(-7960 3825);
DISPLAY 0.723404 (-7960 3825);
PAINT SKYBLUE (-7960 3825);
FORCEPROP 1 LAST PART_NUMBER CS24702FB06
J 0
(-7960 3775);
DISPLAY 0.723404 (-7960 3775);
PAINT WHITE (-7960 3775);
FORCEPROP 1 LAST TOLERANCE 1%
J 0
(-7955 3925);
DISPLAY 0.723404 (-7955 3925);
PAINT SKYBLUE (-7955 3925);
FORCEPROP 1 LAST VALUE 4.7K
J 0
(-7955 3975);
DISPLAY 0.723404 (-7955 3975);
PAINT SKYBLUE (-7955 3975);
FORCEPROP 2 LAST CDS_LIB pure_quanta
J 0
(-8000 3900);
DISPLAY INVISIBLE (-8000 3900);
FORCEPROP 1 LAST PATH I93
J 0
(-7950 4075);
DISPLAY 0.978723 (-7950 4075);
PAINT WHITE (-7950 4075);
DISPLAY INVISIBLE (-7950 4075);
FORCEADD OFFPAGE..4
(-7375 3075);
FORCEPROP 2 LAST $XR1 303 
J 0
(-7069 3075);
DISPLAY 0.638298 (-7069 3075);
PAINT MONO (-7069 3075);
FORCEPROP 2 LAST $XR0 302 
J 0
(-7189 3075);
DISPLAY 0.638298 (-7189 3075);
PAINT MONO (-7189 3075);
FORCEPROP 2 LAST CDS_LIB standard
J 0
(-7375 3075);
DISPLAY INVISIBLE (-7375 3075);
FORCEPROP 1 LAST OFFPAGE TRUE
J 0
(-7050 2950);
DISPLAY 0.872340 (-7050 2950);
PAINT GREEN (-7050 2950);
DISPLAY INVISIBLE (-7050 2950);
FORCEPROP 1 LAST COMMENT_BODY TRUE
J 0
(-7400 2975);
DISPLAY 0.872340 (-7400 2975);
PAINT GREEN (-7400 2975);
DISPLAY INVISIBLE (-7400 2975);
FORCEPROP 2 LAST PATH I94
J 0
(-7050 3125);
DISPLAY 1.021277 (-7050 3125);
DISPLAY INVISIBLE (-7050 3125);
FORCEADD OFFPAGE..5
R 2
(-7375 3400);
FORCEPROP 2 LAST $XR0 215 
J 0
(-7186 3400);
DISPLAY 0.638298 (-7186 3400);
PAINT MONO (-7186 3400);
FORCEPROP 2 LAST CDS_LIB standard
J 0
(-7375 3400);
DISPLAY INVISIBLE (-7375 3400);
FORCEPROP 1 LAST OFFPAGE TRUE
J 2
(-7700 3275);
DISPLAY 0.872340 (-7700 3275);
PAINT AQUA (-7700 3275);
DISPLAY INVISIBLE (-7700 3275);
FORCEPROP 1 LAST COMMENT_BODY TRUE
J 2
(-7475 3325);
DISPLAY 1.170213 (-7475 3325);
PAINT GREEN (-7475 3325);
DISPLAY INVISIBLE (-7475 3325);
FORCEPROP 2 LAST PATH I95
J 0
(-7175 3450);
DISPLAY 1.021277 (-7175 3450);
DISPLAY INVISIBLE (-7175 3450);
FORCEADD OFFPAGE..5
R 2
(-7375 3575);
PAINT RED (-7375 3575);
FORCEPROP 2 LAST $XR0 213 
J 0
(-7186 3575);
DISPLAY 0.638298 (-7186 3575);
PAINT MONO (-7186 3575);
FORCEPROP 2 LAST CDS_LIB standard
J 2
(-7375 3575);
DISPLAY INVISIBLE (-7375 3575);
FORCEPROP 1 LAST OFFPAGE TRUE
J 2
(-7700 3450);
DISPLAY 0.872340 (-7700 3450);
PAINT AQUA (-7700 3450);
DISPLAY INVISIBLE (-7700 3450);
FORCEPROP 1 LAST COMMENT_BODY TRUE
J 2
(-7475 3500);
DISPLAY 1.170213 (-7475 3500);
PAINT GREEN (-7475 3500);
DISPLAY INVISIBLE (-7475 3500);
FORCEPROP 2 LAST PATH I96
J 0
(-7175 3625);
DISPLAY 1.021277 (-7175 3625);
DISPLAY INVISIBLE (-7175 3625);
FORCEADD QUANTA_TITLE_BLOCK_C..1
(-6900 -875);
FORCEPROP 0 LAST CDS_CON_LAST_MODIFIED Fri Mar 11 14:53:40 2022
J 0
(-8785 -860);
PAINT MONO (-8785 -860);
DISPLAY INVISIBLE (-8785 -860);
FORCEPROP 2 LAST CUSTOM_TXT_CDS <XR_PAGE_TITLE>
J 0
(-14790 4375);
DISPLAY 0.638298 (-14790 4375);
PAINT PINK (-14790 4375);
DISPLAY INVISIBLE (-14790 4375);
FORCEPROP 2 LAST CUSTOM_TXT_CDS <CON_LAST_MODIFIED>
J 0
(-8785 -860);
DISPLAY 0.978723 (-8785 -860);
FORCEPROP 2 LAST CUSTOM_TXT_CDS <Q_NUMBER>
J 0
(-8303 -772);
DISPLAY 1.212766 (-8303 -772);
FORCEPROP 2 LAST CUSTOM_TXT_CDS <CON_PAGE_NUM> OF <CON_TOTAL_PAGES>
J 0
(-7346 -857);
DISPLAY 0.978723 (-7346 -857);
FORCEPROP 2 LAST CUSTOM_TXT_CDS <Q_REV>
J 0
(-7084 -772);
DISPLAY 1.212766 (-7084 -772);
FORCEPROP 2 LAST CUSTOM_TXT_CDS <Q_PROJ>
J 0
(-9282 -773);
DISPLAY 1.212766 (-9282 -773);
FORCEPROP 1 LAST CUSTOM_TXT_CDS <NAME_2>
J 0
(-10075 -825);
FORCEPROP 1 LAST CUSTOM_TXT_CDS <NAME_1>
J 0
(-10075 -700);
FORCEPROP 1 LAST Q_TITLE HSC MP5990 (1/4)
J 0
(-16266 -849);
DISPLAY 2.446809 (-16266 -849);
PAINT GREEN (-16266 -849);
FORCEPROP 1 LAST Q_DEPT BU9
J 1
(-10663 -826);
DISPLAY 1.957447 (-10663 -826);
PAINT GREEN (-10663 -826);
FORCEPROP 2 LAST PAGE_BORDER TRUE
J 0
(-14790 4375);
DISPLAY 0.638298 (-14790 4375);
PAINT PINK (-14790 4375);
DISPLAY INVISIBLE (-14790 4375);
FORCEPROP 2 LAST CDS_LIB pure_quanta
J 0
(-6900 -875);
PAINT MONO (-6900 -875);
DISPLAY INVISIBLE (-6900 -875);
FORCEPROP 1 LAST CDS_LMAN_SYM_OUTLINE -9475,6775,100,-125
J 0
(-6900 -875);
DISPLAY 0.468085 (-6900 -875);
PAINT GREEN (-6900 -875);
DISPLAY INVISIBLE (-6900 -875);
FORCEPROP 1 LAST COMMENT_BODY TRUE
J 0
(-6888 -888);
DISPLAY 0.978723 (-6888 -888);
PAINT GREEN (-6888 -888);
DISPLAY INVISIBLE (-6888 -888);
FORCEPROP 2 LAST CDS_XR_PAGE_TITLE CR-301 : @S9S_MB_2U_LIB.S9S_MB_2U(SCH_1):PAGE301
J 0
(-14790 4375);
DISPLAY 0.638298 (-14790 4375);
PAINT PINK (-14790 4375);
DISPLAY INVISIBLE (-14790 4375);
FORCEADD DNS..2
(-12825 2150);
PAINT RED (-12825 2150);
FORCEPROP 2 LAST CDS_LIB mstr_misc
J 0
(-12825 2150);
DISPLAY INVISIBLE (-12825 2150);
FORCEPROP 1 LAST COMMENT_BODY TRUE
R 1
J 0
(-12750 1925);
DISPLAY 0.872340 (-12750 1925);
PAINT GREEN (-12750 1925);
DISPLAY INVISIBLE (-12750 1925);
WIRE 16 -1 (-13375 -50)(-13375 -150);
WIRE 16 -1 (-12750 50)(-12750 -150);
WIRE 16 -1 (-12850 1650)(-12850 1600);
WIRE 16 -1 (-11775 1025)(-11550 1025);
WIRE 16 -1 (-11775 1025)(-11775 825);
WIRE 16 -1 (-15500 -400)(-15500 -475);
WIRE 16 -1 (-11000 1025)(-11000 875);
WIRE 16 -1 (-11000 1025)(-11350 1025);
WIRE 16 -1 (-9975 1300)(-9975 1350);
WIRE 16 -1 (-14575 2750)(-14575 2700);
WIRE 16 -1 (-14575 2750)(-14650 2750);
WIRE 16 -1 (-14225 2800)(-14225 2775);
WIRE 16 -1 (-15225 4225)(-15225 4150);
WIRE 16 -1 (-13325 2075)(-13325 1925);
WIRE 16 -1 (-9975 2050)(-9975 2000);
WIRE 16 -1 (-9625 2975)(-9625 2925);
WIRE 16 -1 (-10050 2975)(-9625 2975);
WIRE 16 -1 (-15025 1050)(-15075 1050);
WIRE 16 -1 (-15075 1050)(-15075 950);
WIRE 16 -1 (-9500 2075)(-9500 2050);
WIRE 16 -1 (-7550 3275)(-7550 3250);
WIRE 16 -1 (-8025 3275)(-7550 3275);
WIRE 16 2175 (-15400 1725)(-14175 1725);
WIRE 16 2175 (-15400 1725)(-15400 825);
WIRE 16 2175 (-14175 1725)(-14175 825);
WIRE 16 2175 (-15400 825)(-14175 825);
WIRE 16 -1 (-14475 -75)(-14800 -75);
WIRE 16 -1 (-14800 -75)(-14800 -150);
WIRE 16 -1 (-14850 -75)(-14800 -75);
WIRE 16 -1 (-14850 150)(-14850 -75);
WIRE 16 -1 (-14850 -75)(-15175 -75);
WIRE 16 -1 (-15175 -75)(-15500 -75);
WIRE 16 -1 (-15175 1100)(-15175 -75);
WIRE 16 -1 (-15025 1100)(-15175 1100);
WIRE 16 -1 (-15625 -75)(-15500 -75);
FORCEPROP 2 LAST SIG_NAME PDB_PRSNT_N
J 0
(-15635 -65);
DISPLAY 0.808511 (-15635 -65);
PAINT WHITE (-15635 -65);
WIRE 16 -1 (-15500 -75)(-15500 -200);
WIRE 16 -1 (-14275 125)(-14275 175);
WIRE 16 -1 (-14275 175)(-13375 175);
WIRE 16 -1 (-13375 650)(-13375 175);
WIRE 16 -1 (-13375 150)(-13375 175);
WIRE 16 -1 (-12750 650)(-13375 650);
FORCEPROP 2 LAST SIG_NAME HSC_EN
J 0
(-12860 660);
DISPLAY 0.723404 (-12860 660);
WIRE 16 -1 (-13375 650)(-13575 650);
WIRE 16 -1 (-12750 650)(-12650 650);
WIRE 16 -1 (-12750 250)(-12750 650);
WIRE 16 -1 (-12375 2225)(-11975 2225);
WIRE 16 -1 (-12375 1950)(-12375 2225);
FORCEPROP 2 LAST SIG_NAME HSC_ADDR
J 0
(-12360 2235);
DISPLAY 0.723404 (-12360 2235);
WIRE 16 -1 (-12375 1950)(-12850 1950);
WIRE 16 -1 (-12850 2050)(-12850 1950);
WIRE 16 -1 (-12850 1850)(-12850 1950);
WIRE 16 -1 (-12850 2375)(-13325 2375);
WIRE 16 -1 (-11975 2375)(-12850 2375);
FORCEPROP 2 LAST SIG_NAME HSC_VDD18
J 0
(-12385 2385);
DISPLAY 0.723404 (-12385 2385);
WIRE 16 -1 (-12850 2375)(-12850 2250);
WIRE 16 -1 (-13325 2375)(-13325 2275);
WIRE 16 -1 (-13000 2525)(-11975 2525);
FORCEPROP 2 LAST SIG_NAME HSC_ON_R
J 0
(-12360 2535);
DISPLAY 0.723404 (-12360 2535);
WIRE 16 -1 (-11975 2775)(-12500 2775);
FORCEPROP 2 LAST SIG_NAME HSC_EN_R
J 0
(-12360 2785);
DISPLAY 0.723404 (-12360 2785);
WIRE 16 -1 (-12500 2775)(-12500 2650);
WIRE 16 -1 (-13000 2650)(-12500 2650);
WIRE 16 -1 (-10825 2075)(-10325 2075);
FORCEPROP 2 LAST SIG_NAME MB0_P12V_STBY_PWRGD
J 0
(-10710 2085);
DISPLAY 0.723404 (-10710 2085);
WIRE 16 -1 (-10325 2075)(-10325 1650);
WIRE 16 -1 (-10325 1650)(-9975 1650);
WIRE 16 -1 (-9975 1650)(-9975 1700);
WIRE 16 -1 (-9975 1550)(-9975 1650);
WIRE 16 -1 (-9975 1700)(-9525 1700);
WIRE 16 -1 (-9975 1700)(-9975 1800);
WIRE 16 -1 (-8350 2675)(-8450 2675);
WIRE 16 -1 (-8450 2675)(-8450 2550);
WIRE 16 -1 (-8925 2675)(-8450 2675);
WIRE 16 -1 (-8925 2525)(-8925 2675);
WIRE 16 -1 (-10825 2675)(-8925 2675);
FORCEPROP 2 LAST SIG_NAME HSC_VTEMP
J 0
(-10710 2685);
DISPLAY 0.808511 (-10710 2685);
WIRE 16 -1 (-9975 3400)(-9050 3400);
WIRE 16 -1 (-9975 3275)(-9975 3400);
WIRE 16 -1 (-9850 3275)(-9975 3275);
WIRE 16 -1 (-10825 3275)(-9975 3275);
FORCEPROP 2 LAST SIG_NAME HSC_D_OC_R
J 0
(-10710 3285);
DISPLAY 0.808511 (-10710 3285);
WIRE 16 -1 (-14525 2500)(-14225 2500);
WIRE 16 -1 (-13775 2500)(-14225 2500);
WIRE 16 -1 (-14225 2575)(-14225 2500);
WIRE 16 -1 (-13775 2975)(-13775 2500);
WIRE 16 -1 (-11975 2975)(-13775 2975);
FORCEPROP 2 LAST SIG_NAME IRQ_SML1_PMBUS_ALERT
J 0
(-12760 2985);
DISPLAY 0.723404 (-12760 2985);
WIRE 16 -1 (-13000 2775)(-12650 2775);
WIRE 16 -1 (-12650 2775)(-12650 2875);
FORCEPROP 2 LAST SIG_NAME HSC_VIN_UVW_N
J 0
(-12535 2885);
DISPLAY 0.723404 (-12535 2885);
WIRE 16 -1 (-12650 2875)(-11975 2875);
WIRE 16 -1 (-14850 350)(-14850 650);
WIRE 16 -1 (-14850 650)(-14050 650);
WIRE 16 -1 (-14050 650)(-13775 650);
WIRE 16 -1 (-14050 875)(-14050 650);
WIRE 16 -1 (-13475 875)(-14050 875);
FORCEPROP 2 LAST SIG_NAME P12V_PSU_FUSE
J 0
(-13935 885);
DISPLAY 0.638298 (-13935 885);
PAINT WHITE (-13935 885);
WIRE 16 -1 (-12225 3325)(-11975 3325);
WIRE 16 -1 (-12225 3325)(-12225 3375);
WIRE 16 -1 (-12225 3375)(-11975 3375);
WIRE 16 -1 (-14400 3375)(-12225 3375);
FORCEPROP 2 LAST SIG_NAME HSC_VDD_R
J 0
(-12435 3385);
DISPLAY 0.808511 (-12435 3385);
WIRE 16 -1 (-14400 3375)(-14400 3875);
WIRE 16 -1 (-14400 3875)(-14925 3875);
WIRE 16 -1 (-14925 3700)(-14925 3875);
WIRE 16 -1 (-15225 3875)(-14925 3875);
WIRE 16 -1 (-15225 3950)(-15225 3875);
WIRE 16 -1 (-15425 3875)(-15225 3875);
WIRE 16 -1 (-15425 3725)(-15425 3875);
WIRE 16 -1 (-15050 3175)(-14625 3175);
FORCEPROP 2 LAST SIG_NAME SMB_SML1_PMBUS_HSC_SCL
J 0
(-15060 3185);
DISPLAY 0.723404 (-15060 3185);
WIRE 16 -1 (-13775 3175)(-14625 3175);
WIRE 16 -1 (-14625 2850)(-14625 3175);
WIRE 16 -1 (-14625 2850)(-14650 2850);
WIRE 16 -1 (-15050 3075)(-14575 3075);
FORCEPROP 2 LAST SIG_NAME SMB_SML1_PMBUS_HSC_SDA
J 0
(-15060 3085);
DISPLAY 0.723404 (-15060 3085);
WIRE 16 -1 (-13775 3075)(-14575 3075);
WIRE 16 -1 (-14575 2800)(-14575 3075);
WIRE 16 -1 (-14650 2800)(-14575 2800);
WIRE 16 -1 (-13700 4000)(-13700 4125);
WIRE 16 -1 (-13700 4125)(-13175 4125);
WIRE 16 -1 (-13700 4125)(-13700 4250);
WIRE 16 -1 (-13175 4125)(-12575 4125);
FORCEPROP 2 LAST SIG_NAME HSC_VSENSE
J 0
(-12460 3585);
DISPLAY 0.808511 (-12460 3585);
WIRE 16 -1 (-13175 4125)(-13175 4000);
WIRE 16 -1 (-12575 4125)(-12575 3575);
WIRE 16 -1 (-12575 3575)(-11975 3575);
WIRE 16 -1 (-14725 2500)(-15750 2500);
FORCEPROP 2 LAST SIG_NAME IRQ_SML1_PMBUS_ALERT_N
J 0
(-15760 2510);
DISPLAY 0.723404 (-15760 2510);
WIRE 16 -1 (-14225 4825)(-14775 4825);
WIRE 16 -1 (-14225 4825)(-13700 4825);
WIRE 16 -1 (-14225 4450)(-14225 4825);
WIRE 16 -1 (-14775 4825)(-14775 4900);
WIRE 16 -1 (-14775 4825)(-14775 4725);
WIRE 16 -1 (-12125 4825)(-13700 4825);
WIRE 16 -1 (-13700 4825)(-13700 4450);
WIRE 16 -1 (-12125 4825)(-12125 4125);
WIRE 16 -1 (-11975 4125)(-12125 4125);
WIRE 16 -1 (-12125 4125)(-12125 4075);
WIRE 16 -1 (-11975 4075)(-12125 4075);
WIRE 16 -1 (-12125 4075)(-12125 4025);
WIRE 16 -1 (-11975 4025)(-12125 4025);
WIRE 16 -1 (-12125 4025)(-12125 3975);
WIRE 16 -1 (-11975 3975)(-12125 3975);
WIRE 16 -1 (-12125 3975)(-12125 3925);
WIRE 16 -1 (-11975 3925)(-12125 3925);
WIRE 16 -1 (-12125 3925)(-12125 3875);
WIRE 16 -1 (-11975 3875)(-12125 3875);
WIRE 16 -1 (-12125 3875)(-12125 3825);
WIRE 16 -1 (-12125 3825)(-11975 3825);
WIRE 16 -1 (-12125 3825)(-12125 3775);
WIRE 16 -1 (-12125 3775)(-11975 3775);
WIRE 16 -1 (-12125 3775)(-12125 3725);
WIRE 16 -1 (-12125 3725)(-11975 3725);
WIRE 16 -1 (-12125 3725)(-12125 3675);
WIRE 16 -1 (-12125 3675)(-11975 3675);
WIRE 16 -1 (-13700 3625)(-13700 3675);
WIRE 16 -1 (-13175 3675)(-13700 3675);
WIRE 16 -1 (-13700 3675)(-13700 3800);
WIRE 16 -1 (-13175 3800)(-13175 3675);
WIRE 16 2175 (-15700 4800)(-14275 4800);
WIRE 16 2175 (-15700 4800)(-15700 4425);
WIRE 16 2175 (-14275 4800)(-14275 4425);
WIRE 16 2175 (-15700 4425)(-14275 4425);
WIRE 16 -1 (-14775 4525)(-14775 4475);
WIRE 16 -1 (-14775 4400)(-14775 4475);
WIRE 16 -1 (-14775 4475)(-15350 4475);
FORCEPROP 2 LAST SIG_NAME P12V_PSU_FUSE
J 0
(-15310 4485);
DISPLAY 0.638298 (-15310 4485);
PAINT WHITE (-15310 4485);
WIRE 16 -1 (-14775 4125)(-14225 4125);
FORCEPROP 0 LAST VOLTAGE 0
J 0
(-14500 4125);
DISPLAY INVISIBLE (-14500 4125);
WIRE 16 -1 (-14775 4125)(-14775 4100);
WIRE 16 -1 (-14775 4150)(-14775 4125);
WIRE 16 -1 (-14225 4250)(-14225 4125);
WIRE 16 -1 (-13475 2525)(-13200 2525);
WIRE 16 -1 (-13475 2150)(-13475 2525);
WIRE 16 -1 (-14250 2150)(-13475 2150);
FORCEPROP 2 LAST SIG_NAME HSC_ON
J 0
(-14235 2160);
DISPLAY 0.723404 (-14235 2160);
WIRE 16 -1 (-13200 2650)(-13600 2650);
FORCEPROP 2 LAST SIG_NAME HSC_EN
J 0
(-14235 2310);
DISPLAY 0.723404 (-14235 2310);
WIRE 16 -1 (-13600 2300)(-13600 2650);
WIRE 16 -1 (-14250 2300)(-13600 2300);
WIRE 16 -1 (-13575 3175)(-11975 3175);
FORCEPROP 2 LAST SIG_NAME SMB_SML1_PMBUS_HSC_L_SCL
J 0
(-12910 3185);
DISPLAY 0.723404 (-12910 3185);
WIRE 16 -1 (-13575 3075)(-11975 3075);
FORCEPROP 2 LAST SIG_NAME SMB_SML1_PMBUS_HSC_R_SDA
J 0
(-12910 3085);
DISPLAY 0.723404 (-12910 3085);
WIRE 16 -1 (-8000 4125)(-8000 4000);
WIRE 16 -1 (-8000 4125)(-8225 4125);
WIRE 16 -1 (-8225 4200)(-8225 4125);
WIRE 16 -1 (-8425 4125)(-8225 4125);
WIRE 16 -1 (-8425 4000)(-8425 4125);
WIRE 16 -1 (-8575 4750)(-8575 4650);
WIRE 16 -1 (-8575 4650)(-9175 4650);
WIRE 16 -1 (-9175 4650)(-9175 4500);
WIRE 16 -1 (-10325 4650)(-9175 4650);
WIRE 16 -1 (-10325 4525)(-10325 4650);
WIRE 16 -1 (-10650 4650)(-10325 4650);
WIRE 16 -1 (-10650 4125)(-10650 4650);
WIRE 16 -1 (-10650 4125)(-10675 4125);
WIRE 16 -1 (-10825 4125)(-10675 4125);
WIRE 16 -1 (-10675 4075)(-10675 4125);
WIRE 16 -1 (-10825 4075)(-10675 4075);
WIRE 16 -1 (-10675 4025)(-10675 4075);
WIRE 16 -1 (-10825 4025)(-10675 4025);
WIRE 16 -1 (-10675 3975)(-10675 4025);
WIRE 16 -1 (-10825 3975)(-10675 3975);
WIRE 16 -1 (-10675 3925)(-10675 3975);
WIRE 16 -1 (-10825 3925)(-10675 3925);
WIRE 16 -1 (-10675 3875)(-10675 3925);
WIRE 16 -1 (-10825 3875)(-10675 3875);
WIRE 16 -1 (-10675 3825)(-10675 3875);
WIRE 16 -1 (-10825 3825)(-10675 3825);
WIRE 16 -1 (-10675 3775)(-10675 3825);
WIRE 16 -1 (-10825 3775)(-10675 3775);
WIRE 16 -1 (-10675 3725)(-10675 3775);
WIRE 16 -1 (-10825 3725)(-10675 3725);
WIRE 16 -1 (-10675 3675)(-10675 3725);
WIRE 16 -1 (-10825 3675)(-10675 3675);
WIRE 16 -1 (-9125 3825)(-9125 3950);
WIRE 16 -1 (-9125 3825)(-9175 3825);
WIRE 16 -1 (-9175 3775)(-9175 3825);
WIRE 16 -1 (-9175 3825)(-9225 3825);
WIRE 16 -1 (-9225 3950)(-9225 3825);
WIRE 16 -1 (-7625 2725)(-8100 2725);
WIRE 16 -1 (-7625 2775)(-7625 2725);
WIRE 16 -1 (-7625 2650)(-7625 2725);
WIRE 16 -1 (-8100 2725)(-8100 2750);
WIRE 16 -1 (-7425 3075)(-7625 3075);
WIRE 16 -1 (-7625 3075)(-8100 3075);
WIRE 16 -1 (-7625 3075)(-7625 2975);
WIRE 16 -1 (-8100 2950)(-8100 3075);
WIRE 16 -1 (-10825 3075)(-8100 3075);
FORCEPROP 2 LAST SIG_NAME HSC_IMON
J 0
(-10710 3085);
DISPLAY 0.808511 (-10710 3085);
WIRE 16 -1 (-8450 2350)(-8450 2225);
WIRE 16 -1 (-8450 2225)(-8625 2225);
WIRE 16 -1 (-8625 2150)(-8625 2225);
WIRE 16 -1 (-8925 2225)(-8625 2225);
WIRE 16 -1 (-8925 2225)(-8925 2325);
WIRE 16 -1 (-8000 3800)(-8000 3575);
WIRE 16 -1 (-7425 3575)(-8000 3575);
FORCEPROP 2 LAST SIG_NAME IRQ_HSC_FAULT_N
J 0
(-7935 3585);
DISPLAY 0.723404 (-7935 3585);
WIRE 16 -1 (-8850 3575)(-8000 3575);
WIRE 16 -1 (-8425 3800)(-8425 3400);
WIRE 16 -1 (-8425 3400)(-7425 3400);
FORCEPROP 2 LAST SIG_NAME HSC_D_OC
J 0
(-7735 3410);
DISPLAY 0.808511 (-7735 3410);
WIRE 16 -1 (-8850 3400)(-8425 3400);
WIRE 16 -1 (-8525 3275)(-8225 3275);
WIRE 16 -1 (-8525 3175)(-8525 3275);
WIRE 16 -1 (-10825 3175)(-8525 3175);
FORCEPROP 2 LAST SIG_NAME HSC_MODE
J 0
(-10710 3185);
DISPLAY 0.808511 (-10710 3185);
WIRE 16 -1 (-9500 2375)(-9425 2375);
WIRE 16 -1 (-9500 2375)(-9500 2275);
WIRE 16 -1 (-10825 2375)(-9500 2375);
FORCEPROP 2 LAST SIG_NAME HSC_SS
J 0
(-10710 2385);
DISPLAY 0.808511 (-10710 2385);
WIRE 16 -1 (-9775 3775)(-10250 3775);
WIRE 16 -1 (-9775 3875)(-9775 3775);
WIRE 16 -1 (-9775 3725)(-9775 3775);
WIRE 16 -1 (-10250 3775)(-10250 3875);
WIRE 16 -1 (-9775 4200)(-10250 4200);
WIRE 16 -1 (-9775 4200)(-9775 4075);
WIRE 16 -1 (-10250 4075)(-10250 4200);
WIRE 16 -1 (-10325 4200)(-10250 4200);
WIRE 16 -1 (-10325 4200)(-10325 4325);
WIRE 16 -1 (-10350 4200)(-10325 4200);
WIRE 16 -1 (-10350 3575)(-10350 4200);
WIRE 16 -1 (-10825 3575)(-10350 3575);
WIRE 16 -1 (-10100 3575)(-9050 3575);
WIRE 16 -1 (-10100 3475)(-10100 3575);
WIRE 16 -1 (-9850 3475)(-10100 3475);
WIRE 16 -1 (-10100 3375)(-10100 3475);
WIRE 16 -1 (-10825 3375)(-10100 3375);
FORCEPROP 2 LAST SIG_NAME HSC_FAULT
J 0
(-10710 3385);
DISPLAY 0.808511 (-10710 3385);
WIRE 16 -1 (-10825 2975)(-10250 2975);
FORCEPROP 2 LAST SIG_NAME HSC_CS
J 0
(-10710 2985);
DISPLAY 0.808511 (-10710 2985);
WIRE 16 -1 (-10825 2575)(-10200 2575);
FORCEPROP 2 LAST SIG_NAME HSC_OCREF
J 0
(-10710 2585);
DISPLAY 0.808511 (-10710 2585);
WIRE 16 -1 (-10825 2475)(-10200 2475);
FORCEPROP 2 LAST SIG_NAME HSC_SCREF
J 0
(-10710 2485);
DISPLAY 0.808511 (-10710 2485);
WIRE 16 -1 (-10825 2275)(-10200 2275);
FORCEPROP 2 LAST SIG_NAME HSC_FLT_TYPE
J 0
(-10710 2285);
DISPLAY 0.808511 (-10710 2285);
WIRE 16 -1 (-12075 2075)(-12075 2025);
WIRE 16 -1 (-11975 2075)(-12075 2075);
WIRE 16 -1 (-11975 2025)(-12075 2025);
WIRE 16 -1 (-12075 2025)(-12075 1975);
WIRE 16 -1 (-13600 2800)(-13600 2775);
WIRE 16 -1 (-13600 2775)(-13200 2775);
WIRE 16 -1 (-15425 3525)(-15425 3450);
WIRE 16 -1 (-15425 3450)(-14925 3450);
WIRE 16 -1 (-14925 3450)(-14925 3500);
WIRE 16 -1 (-14925 3400)(-14925 3450);
WIRE 16 -1 (-14275 -450)(-14275 -475);
WIRE 16 -1 (-14275 -275)(-14275 -450);
WIRE 16 -1 (-14800 -450)(-14275 -450);
WIRE 16 -1 (-14800 -350)(-14800 -450);
DOT 1 (-12850 1950);
DOT 1 (-9975 1650);
DOT 1 (-14775 4125);
DOT 1 (-13700 3675);
DOT 1 (-8225 4125);
DOT 1 (-9175 4650);
DOT 1 (-9175 3825);
DOT 1 (-7625 3075);
DOT 1 (-7625 2725);
DOT 1 (-8000 3575);
DOT 1 (-8425 3400);
DOT 1 (-8100 3075);
DOT 1 (-8450 2675);
DOT 1 (-8925 2675);
DOT 1 (-8625 2225);
DOT 1 (-9500 2375);
DOT 1 (-9775 3775);
DOT 1 (-10250 4200);
DOT 1 (-10325 4650);
DOT 1 (-10325 4200);
DOT 1 (-10675 4125);
DOT 1 (-10675 4075);
DOT 1 (-10675 3975);
DOT 1 (-10675 4025);
DOT 1 (-10675 3925);
DOT 1 (-10675 3875);
DOT 1 (-10675 3825);
DOT 1 (-10675 3775);
DOT 1 (-10675 3725);
DOT 1 (-9975 3275);
DOT 1 (-10100 3475);
DOT 1 (-9975 1700);
DOT 1 (-12125 4075);
DOT 1 (-12125 4125);
DOT 1 (-12125 3975);
DOT 1 (-12125 4025);
DOT 1 (-12125 3925);
DOT 1 (-12125 3875);
DOT 1 (-12125 3825);
DOT 1 (-12125 3775);
DOT 1 (-12125 3725);
DOT 1 (-13175 4125);
DOT 1 (-12225 3375);
DOT 1 (-12075 2025);
DOT 1 (-12850 2375);
DOT 1 (-13700 4825);
DOT 1 (-14225 4825);
DOT 1 (-13700 4125);
DOT 1 (-14775 4825);
DOT 1 (-14775 4475);
DOT 1 (-14925 3875);
DOT 1 (-15225 3875);
DOT 1 (-14625 3175);
DOT 1 (-14575 3075);
DOT 1 (-14225 2500);
DOT 1 (-14925 3450);
DOT 1 (-12750 650);
DOT 1 (-13375 650);
DOT 1 (-13375 175);
DOT 1 (-14050 650);
DOT 1 (-14850 -75);
DOT 1 (-14800 -75);
DOT 1 (-15175 -75);
DOT 1 (-15500 -75);
DOT 1 (-14275 -450);
FORCENOTE
EN>1.2V ON
(-12475 2675) 0;
DISPLAY LEFT (-12475 2675);
DISPLAY 1.021277 (-12475 2675);
FORCENOTE
EN<0.95V OFF
(-12475 2600) 0;
DISPLAY LEFT (-12475 2600);
DISPLAY 1.021277 (-12475 2600);
FORCENOTE
20211208 ADD FS1 
(-16075 4850) 0;
DISPLAY LEFT (-16075 4850);
DISPLAY 1.595745 (-16075 4850);
PAINT PINK (-16075 4850);
FORCENOTE
20211203 CHANGE JP4003 CONNECT 
(-15725 1775) 0;
DISPLAY LEFT (-15725 1775);
DISPLAY 1.595745 (-15725 1775);
PAINT PINK (-15725 1775);
FORCENOTE
JUMPER 1-2
(-14900 1500) 0;
DISPLAY LEFT (-14900 1500);
DISPLAY 1.276596 (-14900 1500);
PAINT WHITE (-14900 1500);
FORCENOTE
VOUT SLEW RATE: 2V/MS
(-9175 1784) 0;
DISPLAY LEFT (-9175 1784);
DISPLAY 1.021277 (-9175 1784);
FORCENOTE
SOFT START TIME=6MS.
(-9175 1850) 0;
DISPLAY LEFT (-9175 1850);
DISPLAY 1.021277 (-9175 1850);
FORCENOTE
7BITS ADDRESS 0X20H
(-11850 1750) 0;
DISPLAY LEFT (-11850 1750);
DISPLAY 1.021277 (-11850 1750);
FORCENOTE
20211112 MODIFY FOR GT
(-14425 5550) 0;
DISPLAY LEFT (-14425 5550);
DISPLAY 2.510638 (-14425 5550);
PAINT PINK (-14425 5550);
FORCENOTE
FPH=220A
(-15400 5434) 0;
DISPLAY LEFT (-15400 5434);
DISPLAY 1.595745 (-15400 5434);
FORCENOTE
HOT SWAT CIRCUIT
(-16121 5613) 0;
DISPLAY LEFT (-16121 5613);
DISPLAY 2.000000 (-16121 5613);
FORCENOTE
OCP=240A
(-16125 5509) 0;
DISPLAY LEFT (-16125 5509);
DISPLAY 1.595745 (-16125 5509);
FORCENOTE
LATCH OFF MODE
(-16100 5175) 0;
DISPLAY LEFT (-16100 5175);
DISPLAY 1.021277 (-16100 5175);
FORCENOTE
ADDRESS 0X20
(-16100 5241) 0;
DISPLAY LEFT (-16100 5241);
DISPLAY 1.021277 (-16100 5241);
FORCENOTE
UV =10.091V
(-16100 5300) 0;
DISPLAY LEFT (-16100 5300);
DISPLAY 1.021277 (-16100 5300);
FORCENOTE
OV =14.333V
(-16100 5350) 0;
DISPLAY LEFT (-16100 5350);
DISPLAY 1.021277 (-16100 5350);
FORCENOTE
OCW=220A
(-16125 5434) 0;
DISPLAY LEFT (-16125 5434);
DISPLAY 1.595745 (-16125 5434);
QUIT
